G04 ================== begin FILE IDENTIFICATION RECORD ==================*
G04 Layout Name:  13130-1b.brd*
G04 Film Name:    DIF_REF_L10*
G04 File Format:  Gerber RS274X*
G04 File Origin:  Cadence Allegro 16.5-S037*
G04 Origin Date:  Thu Nov 13 18:47:02 2014*
G04 *
G04 Layer:  BOARD GEOMETRY/OUTLINE*
G04 Layer:  BOARD GEOMETRY/DIF_REF_L10*
G04 Layer:  BOARD GEOMETRY/PANEL_OUTLINE*
G04 *
G04 Offset:    (0.00 0.00)*
G04 Mirror:    No*
G04 Mode:      Positive*
G04 Rotation:  0*
G04 FullContactRelief:  No*
G04 UndefLineWidth:     6.00*
G04 ================== end FILE IDENTIFICATION RECORD ====================*
%FSLAX35Y35*MOIN*%
%IR0*IPPOS*OFA0.00000B0.00000*MIA0B0*SFA1.00000B1.00000*%
%ADD10C,.004*%
%ADD11C,.005*%
%ADD12C,.006*%
%ADD13C,.0045*%
%ADD14C,.0075*%
G75*
%LPD*%
G75*
G54D10*
G01X305750Y205300D02*
X305500Y205050D01*
G01X306768Y205300D02*
X305750D01*
G01X307768Y204300D02*
X306768Y205300D01*
G01X309068Y204300D02*
X307768D01*
G01X309458Y203910D02*
X309068Y204300D01*
G01X310658Y203910D02*
X309458D01*
G01X305750Y206100D02*
X305500Y206350D01*
G01X307100Y206100D02*
X305750D01*
G01X308100Y205100D02*
X307100Y206100D01*
G01X324468Y205100D02*
X308100D01*
G01X322400Y177050D02*
X322300D01*
G01X322650Y177300D02*
X322400Y177050D01*
G01X324600Y177300D02*
X322650D01*
G01X330002Y182702D02*
X324600Y177300D01*
G01X322400Y178350D02*
X322300D01*
G01X322650Y178100D02*
X322400Y178350D01*
G01X324268Y178100D02*
X322650D01*
G01X329670Y183502D02*
X324268Y178100D01*
G01X315850Y197270D02*
X315800D01*
G01X316100Y197520D02*
X315850Y197270D01*
G01X319222Y197520D02*
X316100D01*
G01X323142Y193600D02*
X319222Y197520D01*
G01X324550Y193600D02*
X323142D01*
G01X326550Y191600D02*
X324550Y193600D01*
G01X323474Y194400D02*
X319554Y198320D01*
G01X324882Y194400D02*
X323474D01*
G01X325666Y193616D02*
X324882Y194400D01*
G01X323200Y213100D02*
Y214700D01*
G01X324049Y212251D02*
X323200Y213100D01*
G01X324049Y211700D02*
Y212251D01*
G01X324897Y210851D02*
X324049Y211700D01*
G01X325449Y210851D02*
X324897D01*
G01X326297Y210003D02*
X325449Y210851D01*
G01X331450Y205982D02*
X324000Y213432D01*
G01X311048Y204300D02*
X310658Y203910D01*
G01X312248Y204300D02*
X311048D01*
G01X312638Y203910D02*
X312248Y204300D01*
G01X313838Y203910D02*
X312638D01*
G01X314228Y204300D02*
X313838Y203910D01*
G01X318640Y204300D02*
X314228D01*
G01X319030Y203910D02*
X318640Y204300D01*
G01X320230Y203910D02*
X319030D01*
G01X320620Y204300D02*
X320230Y203910D01*
G01X321820Y204300D02*
X320620D01*
G01X322210Y203910D02*
X321820Y204300D01*
G01X323410Y203910D02*
X322210D01*
G01X323800Y204300D02*
X323410Y203910D01*
G01X324800Y204300D02*
X323800D01*
G01X326182Y205682D02*
X324800Y204300D01*
G01X325850Y206482D02*
X324468Y205100D01*
G01X316150Y199818D02*
X316100D01*
G01X316400Y200068D02*
X316150Y199818D01*
G01X317600Y200068D02*
X316400D01*
G01X317990Y199678D02*
X317600Y200068D01*
G01X319190Y199678D02*
X317990D01*
G01X319580Y200068D02*
X319190Y199678D01*
G01X324100Y200068D02*
X319580D01*
G01X326599Y197569D02*
X324100Y200068D01*
G01X316150Y201118D02*
X316100D01*
G01X316400Y200868D02*
X316150Y201118D01*
G01X324432Y200868D02*
X316400D01*
G01X326931Y198369D02*
X324432Y200868D01*
G01X315850Y198570D02*
X315800D01*
G01X316100Y198320D02*
X315850Y198570D01*
G01X319554Y198320D02*
X316100D01*
G01X320839Y220100D02*
X320300D01*
G01X321089Y220350D02*
X320839Y220100D01*
G01X322250Y220350D02*
X321089D01*
G01X323203Y219397D02*
X322250Y220350D01*
G01X323203Y218846D02*
Y219397D01*
G01X324051Y217997D02*
X323203Y218846D01*
G01X324603Y217997D02*
X324051D01*
G01X325451Y217149D02*
X324603Y217997D01*
G01X325451Y216597D02*
Y217149D01*
G01X326300Y215749D02*
X325451Y216597D01*
G01X320839Y221400D02*
X320300D01*
G01X321089Y221150D02*
X320839Y221400D01*
G01X322582Y221150D02*
X321089D01*
G01X328500Y215232D02*
X322582Y221150D01*
G01X314777Y216491D02*
X314706Y216420D01*
G01X314777Y216845D02*
Y216491D01*
G01X315732Y217800D02*
X314777Y216845D01*
G01X316920Y217800D02*
X315732D01*
G01X317310Y217410D02*
X316920Y217800D01*
G01X318510Y217410D02*
X317310D01*
G01X318900Y217800D02*
X318510Y217410D01*
G01X320100Y217800D02*
X318900D01*
G01X320951Y216949D02*
X320100Y217800D01*
G01X320951Y216397D02*
Y216949D01*
G01X321800Y215549D02*
X320951Y216397D01*
G01X322351Y215549D02*
X321800D01*
G01X323200Y214700D02*
X322351Y215549D01*
G01X314139Y217339D02*
X313786D01*
G01X315400Y218600D02*
X314139Y217339D01*
G01X320432Y218600D02*
X315400D01*
G01X324000Y215032D02*
X320432Y218600D01*
G01X324000Y213432D02*
Y215032D01*
G01X340868Y181000D02*
X339166Y182702D01*
G01X342068Y181000D02*
X340868D01*
G01X341200Y181800D02*
X339498Y183502D01*
G01X339500Y191700D02*
Y198168D01*
G01X340400Y190800D02*
X339500Y191700D01*
G01X341566Y190800D02*
X340400D01*
G01X340300Y192032D02*
Y198500D01*
G01X340732Y191600D02*
X340300Y192032D01*
G01X341714Y191600D02*
X340732D01*
G01X333100Y195368D02*
Y201200D01*
G01X335446Y193022D02*
X333100Y195368D01*
G01X335446Y191054D02*
Y193022D01*
G01X336300Y190200D02*
X335446Y191054D01*
G01X336800Y190200D02*
X336300D01*
G01X337800Y189200D02*
X336800Y190200D01*
G01X333900Y195700D02*
Y201532D01*
G01X336246Y193354D02*
X333900Y195700D01*
G01X336246Y191386D02*
Y193354D01*
G01X336632Y191000D02*
X336246Y191386D01*
G01X337198Y191000D02*
X336632D01*
G01X337800Y191602D02*
X337198Y191000D01*
G01X337800Y192200D02*
Y191602D01*
G01X331500Y193036D02*
Y199611D01*
G01X331132Y192668D02*
X331500Y193036D01*
G01X331132Y191368D02*
Y192668D01*
G01X332168Y190332D02*
X331132Y191368D01*
G01X333758Y190332D02*
X332168D01*
G01X334707Y189383D02*
X333758Y190332D01*
G01X332300Y192704D02*
Y199943D01*
G01X331932Y192336D02*
X332300Y192704D01*
G01X331932Y191700D02*
Y192336D01*
G01X332500Y191132D02*
X331932Y191700D01*
G01X333066Y191132D02*
X332500D01*
G01X333996Y192062D02*
X333066Y191132D01*
G01X333996Y192063D02*
Y192062D01*
G01X327432Y197569D02*
X326599D01*
G01X328522Y196479D02*
X327432Y197569D01*
G01X328522Y195009D02*
Y196479D01*
G01X329972Y193559D02*
X328522Y195009D01*
G01X329733Y196400D02*
X327764Y198369D01*
G01X329972Y196400D02*
X329733D01*
G01X326566Y193616D02*
X325666D01*
G01X326850Y193900D02*
X326566Y193616D01*
G01X339166Y182702D02*
X330002D01*
G01X339498Y183502D02*
X329670D01*
G01X327700Y212100D02*
Y214900D01*
G01X329203Y210597D02*
X327700Y212100D01*
G01X329203Y210046D02*
Y210597D01*
G01X330051Y209197D02*
X329203Y210046D01*
G01X330603Y209197D02*
X330051D01*
G01X331451Y208349D02*
X330603Y209197D01*
G01X331451Y207797D02*
Y208349D01*
G01X332300Y206949D02*
X331451Y207797D01*
G01X332851Y206949D02*
X332300D01*
G01X333700Y206100D02*
X332851Y206949D01*
G01X333700Y203968D02*
Y206100D01*
G01X337251Y200417D02*
X333700Y203968D01*
G01X337251Y199865D02*
Y200417D01*
G01X338100Y199017D02*
X337251Y199865D01*
G01X338651Y199017D02*
X338100D01*
G01X339500Y198168D02*
X338651Y199017D01*
G01X328500Y212432D02*
Y215232D01*
G01X334500Y206432D02*
X328500Y212432D01*
G01X334500Y204300D02*
Y206432D01*
G01X340300Y198500D02*
X334500Y204300D01*
G01X326297Y209451D02*
Y210003D01*
G01X327146Y208603D02*
X326297Y209451D01*
G01X327697Y208603D02*
X327146D01*
G01X330650Y205650D02*
X327697Y208603D01*
G01X330650Y203650D02*
Y205650D01*
G01X333100Y201200D02*
X330650Y203650D01*
G01X331450Y203982D02*
Y205982D01*
G01X333900Y201532D02*
X331450Y203982D01*
G01X327787Y205682D02*
X326182D01*
G01X328996Y204473D02*
X327787Y205682D01*
G01X328996Y202115D02*
Y204473D01*
G01X331500Y199611D02*
X328996Y202115D01*
G01X328119Y206482D02*
X325850D01*
G01X329796Y204805D02*
X328119Y206482D01*
G01X329796Y202447D02*
Y204805D01*
G01X332300Y199943D02*
X329796Y202447D01*
G01X327764Y198369D02*
X326931D01*
G01X341500Y211600D02*
X339600Y213500D01*
G01X334110Y212210D02*
Y213410D01*
G01X334500Y211820D02*
X334110Y212210D01*
G01X334500Y208700D02*
Y211820D01*
G01X342150Y201050D02*
X334500Y208700D01*
G01X335300Y209032D02*
Y215532D01*
G01X342950Y201382D02*
X335300Y209032D01*
G01X326851Y215749D02*
X326300D01*
G01X327700Y214900D02*
X326851Y215749D01*
G01X330520Y222880D02*
X330449Y222951D01*
G01X330874Y222880D02*
X330520D01*
G01X332554Y221200D02*
X330874Y222880D01*
G01X336800Y221200D02*
X332554D01*
G01X339600Y218400D02*
X336800Y221200D01*
G01X339600Y213500D02*
Y218400D01*
G01X331439Y223800D02*
X331368Y223871D01*
G01X331439Y223799D02*
Y223800D01*
G01X331438Y223798D02*
X331439Y223799D01*
G01X331438Y223448D02*
Y223798D01*
G01X332886Y222000D02*
X331438Y223448D01*
G01X337132Y222000D02*
X332886D01*
G01X340400Y218732D02*
X337132Y222000D01*
G01X340400Y213832D02*
Y218732D01*
G01X342300Y211932D02*
X340400Y213832D01*
G01X326640Y223059D02*
X326287D01*
G01X330003Y219695D02*
X326640Y223059D01*
G01X330003Y219143D02*
Y219695D01*
G01X330851Y218295D02*
X330003Y219143D01*
G01X331403Y218295D02*
X330851D01*
G01X332251Y217446D02*
X331403Y218295D01*
G01X334498Y215199D02*
X332251Y217446D01*
G01X334500Y215199D02*
X334498D01*
G01X334500Y213800D02*
Y215199D01*
G01X334110Y213410D02*
X334500Y213800D01*
G01X327277Y223909D02*
X327207Y223979D01*
G01X327277Y223555D02*
Y223909D01*
G01X335300Y215532D02*
X327277Y223555D01*
G01X338876Y225524D02*
X344300Y220100D01*
G01X338522Y225524D02*
X338876D01*
G01X338486Y225560D02*
X338522Y225524D01*
G01X339405Y226127D02*
Y226480D01*
G01X344632Y220900D02*
X339405Y226127D01*
G01X333446Y224468D02*
X333093D01*
G01X334414Y223500D02*
X333446Y224468D01*
G01X337768Y223500D02*
X334414D01*
G01X343068Y218200D02*
X337768Y223500D01*
G01X334395Y225005D02*
X334013Y225387D01*
G01X334395Y224651D02*
Y225005D01*
G01X334746Y224300D02*
X334395Y224651D01*
G01X338100Y224300D02*
X334746D01*
G01X343400Y219000D02*
X338100Y224300D01*
G01X342458Y180610D02*
X342068Y181000D01*
G01X343658Y180610D02*
X342458D01*
G01X344048Y181000D02*
X343658Y180610D01*
G01X346132Y181000D02*
X344048D01*
G01X346981Y181849D02*
X346132Y181000D01*
G01X347532Y181849D02*
X346981D01*
G01X348381Y182697D02*
X347532Y181849D01*
G01X345800Y181800D02*
X341200D01*
G01X348958Y184958D02*
X345800Y181800D01*
G01X342342Y190024D02*
X341566Y190800D01*
G01X342339Y192225D02*
X341714Y191600D01*
G01X347296Y197814D02*
Y203572D01*
G01X346906Y197424D02*
X347296Y197814D01*
G01X346906Y196224D02*
Y197424D01*
G01X347296Y195834D02*
X346906Y196224D01*
G01X347296Y191504D02*
Y195834D01*
G01X349100Y189700D02*
X347296Y191504D01*
G01X348096Y192821D02*
Y203904D01*
G01X349017Y191900D02*
X348096Y192821D01*
G01X349100Y191900D02*
X349017D01*
G01X344053Y191947D02*
Y198326D01*
G01X345500Y190500D02*
X344053Y191947D01*
G01X344853Y194124D02*
Y198658D01*
G01X345503Y193474D02*
X344853Y194124D01*
G01X355075Y194925D02*
X356700Y193300D01*
G01X355075Y198224D02*
Y194925D01*
G01X355875Y197892D02*
X357150Y199167D01*
G01X355875Y196425D02*
Y197892D01*
G01X356600Y195700D02*
X355875Y196425D01*
G01X352159Y193511D02*
Y202296D01*
G01X353625Y192045D02*
X352159Y193511D01*
G01X352959Y195711D02*
Y207091D01*
G01X353625Y195045D02*
X352959Y195711D01*
G01X348381Y183249D02*
Y182697D01*
G01X349290Y184158D02*
X348381Y183249D01*
G01X352137Y184158D02*
X349290D01*
G01X353302Y182993D02*
X352137Y184158D01*
G01X352176Y184958D02*
X348958D01*
G01X353342Y186124D02*
X352176Y184958D01*
G01X341500Y209368D02*
Y211600D01*
G01X347296Y203572D02*
X341500Y209368D01*
G01X342300Y209700D02*
Y211932D01*
G01X348096Y203904D02*
X342300Y209700D01*
G01X342150Y200229D02*
Y201050D01*
G01X344053Y198326D02*
X342150Y200229D01*
G01X342950Y200561D02*
Y201382D01*
G01X344853Y198658D02*
X342950Y200561D01*
G01X356350Y199499D02*
X355075Y198224D01*
G01X355960Y202848D02*
X356350Y202458D01*
G01X355960Y204048D02*
Y202848D01*
G01X356350Y204438D02*
X355960Y204048D01*
G01Y206028D02*
X356350Y205638D01*
G01X355960Y207228D02*
Y206028D01*
G01X356350Y207618D02*
X355960Y207228D01*
G01X355400Y209768D02*
X356350Y208818D01*
G01X355400Y213700D02*
Y209768D01*
G01X356200Y210100D02*
Y214032D01*
G01X357150Y209150D02*
X356200Y210100D01*
G01X349350Y209568D02*
Y215018D01*
G01X352159Y206759D02*
X349350Y209568D01*
G01X352159Y204276D02*
Y206759D01*
G01X351769Y203886D02*
X352159Y204276D01*
G01X351769Y202686D02*
Y203886D01*
G01X352159Y202296D02*
X351769Y202686D01*
G01X350150Y209900D02*
Y215350D01*
G01X352959Y207091D02*
X350150Y209900D01*
G01X352649Y216451D02*
X355400Y213700D01*
G01X352097Y216451D02*
X352649D01*
G01X351249Y217300D02*
X352097Y216451D01*
G01X351249Y217851D02*
Y217300D01*
G01X349000Y220100D02*
X351249Y217851D01*
G01X344300Y220100D02*
X349000D01*
G01X349332Y220900D02*
X344632D01*
G01X356200Y214032D02*
X349332Y220900D01*
G01X346168Y218200D02*
X343068D01*
G01X349350Y215018D02*
X346168Y218200D01*
G01X346500Y219000D02*
X343400D01*
G01X350150Y215350D02*
X346500Y219000D01*
G01X356350Y202458D02*
Y199499D01*
G01Y205638D02*
Y204438D01*
G01Y208818D02*
Y207618D01*
G01X357150Y199167D02*
Y209150D01*
G01X417346Y114396D02*
X420260Y117310D01*
G01X417346Y111818D02*
Y114396D01*
G01X418195Y110969D02*
X417346Y111818D01*
G01X430900Y99097D02*
Y106921D01*
G01X432628Y97369D02*
X430900Y99097D01*
G01X432628Y96538D02*
Y97369D01*
G01X431700Y99429D02*
Y107253D01*
G01X433329Y97800D02*
X431700Y99429D01*
G01X433700Y97800D02*
X433329D01*
G01X433096Y104872D02*
Y107572D01*
G01X437034Y100934D02*
X433096Y104872D01*
G01X428400Y104770D02*
X427560D01*
G01X428690Y104480D02*
X428400Y104770D01*
G01X428690Y96732D02*
Y104480D01*
G01X431200Y94222D02*
X428690Y96732D01*
G01X431200Y92468D02*
Y94222D01*
G01X432509Y91159D02*
X431200Y92468D01*
G01X432509Y90209D02*
Y91159D01*
G01X432000Y92800D02*
X433424Y91376D01*
G01X432000Y94554D02*
Y92800D01*
G01X429490Y97064D02*
X432000Y94554D01*
G01X429490Y105952D02*
Y97064D01*
G01X420600Y118071D02*
Y118300D01*
G01X420260Y117310D02*
X420600Y118071D01*
G01X418195Y110418D02*
Y110969D01*
G01X419043Y109569D02*
X418195Y110418D01*
G01X419595Y109569D02*
X419043D01*
G01X421201Y107963D02*
X419595Y109569D01*
G01X421863Y107963D02*
X421201D01*
G01X421864Y107964D02*
X421863Y107963D01*
G01X426263Y107964D02*
X421864D01*
G01X426653Y107574D02*
X426263Y107964D01*
G01X427853Y107574D02*
X426653D01*
G01X428243Y107964D02*
X427853Y107574D01*
G01X429857Y107964D02*
X428243D01*
G01X430900Y106921D02*
X429857Y107964D01*
G01X421886Y119386D02*
X420672Y120600D01*
G01X422300Y118300D02*
G03X421886Y119386I-1631J0D01*
G01X422100Y117400D02*
G03X422300Y118300I-1925J900D01*
G01X421900Y117200D02*
X422100Y117400D01*
G01X420782Y116700D02*
G03X421900Y117200I0J1500D01*
G01X418146Y114064D02*
X420782Y116700D01*
G01X418146Y112150D02*
Y114064D01*
G01X421532Y108764D02*
X418146Y112150D01*
G01X430189Y108764D02*
X421532D01*
G01X431700Y107253D02*
X430189Y108764D01*
G01X422801Y114407D02*
X422042Y115224D01*
G01X422801Y112467D02*
Y114407D01*
G01X425468Y109800D02*
X422801Y112467D01*
G01X430868Y109800D02*
X425468D01*
G01X433096Y107572D02*
X430868Y109800D01*
G01X431200Y110600D02*
X433896Y107904D01*
G01X425800Y110600D02*
X431200D01*
G01X423601Y112799D02*
X425800Y110600D01*
G01X423601Y113901D02*
Y112799D01*
G01X424700Y115000D02*
X423601Y113901D01*
G01X428130Y114530D02*
X427900Y114300D01*
G01X429230Y114530D02*
X428130D01*
G01X429905Y113855D02*
X429230Y114530D01*
G01X430824Y113855D02*
X429905D01*
G01X436396Y108283D02*
X430824Y113855D01*
G01X431156Y114655D02*
X437196Y108615D01*
G01X430237Y114655D02*
X431156D01*
G01X428392Y116500D02*
X430237Y114655D01*
G01X428100Y116500D02*
X428392D01*
G01X429105Y106337D02*
X429490Y105952D01*
G01X430500Y142081D02*
X430694Y142275D01*
G01X430500Y140716D02*
Y142081D01*
G01X430916Y140300D02*
X430500Y140716D01*
G01X432100Y140300D02*
X430916D01*
G01X432600Y140800D02*
X432100Y140300D01*
G01X432600Y143200D02*
Y140800D01*
G01X433800Y144400D02*
X432600Y143200D01*
G01X429331Y140000D02*
X428390Y139059D01*
G01X430084Y140000D02*
X429331D01*
G01X430584Y139500D02*
X430084Y140000D01*
G01X432432Y139500D02*
X430584D01*
G01X433400Y140468D02*
X432432Y139500D01*
G01X434132Y143600D02*
X433400Y142868D01*
G01X437034Y100559D02*
Y100934D01*
G01X436575Y100100D02*
X437034Y100559D01*
G01X437834Y100491D02*
X438225Y100100D01*
G01X437834Y101266D02*
Y100491D01*
G01X433896Y105204D02*
X437834Y101266D01*
G01X433896Y107904D02*
Y105204D01*
G01X440539Y101878D02*
X436396Y106021D01*
G01X440539Y101355D02*
Y101878D01*
G01X440575Y101319D02*
X440539Y101355D01*
G01X441063Y102486D02*
X441742D01*
G01X437196Y106353D02*
X441063Y102486D01*
G01X433424Y91376D02*
X433676D01*
G01X436396Y106021D02*
Y108283D01*
G01X437196Y108615D02*
Y106353D01*
G01X437300Y144400D02*
X433800D01*
G01X433400Y142868D02*
Y140468D01*
G01X436544Y143600D02*
X434132D01*
G01X436644Y143500D02*
X436544Y143600D01*
G54D11*
G01X90700Y205200D02*
X89500Y204000D01*
G01X90700Y207915D02*
Y205200D01*
G01X100035Y217250D02*
X90700Y207915D01*
G01X92800Y204108D02*
X92900Y204008D01*
G01X92800Y204207D02*
Y204108D01*
G01X91700Y205307D02*
X92800Y204207D01*
G01X91700Y207500D02*
Y205307D01*
G01X100450Y216250D02*
X91700Y207500D01*
G01X223693Y217250D02*
X100035D01*
G01X224108Y216250D02*
X100450D01*
G01X238893Y232450D02*
X223693Y217250D01*
G01X239308Y231450D02*
X224108Y216250D01*
G01X249435Y232450D02*
X238893D01*
G01X249850Y231450D02*
X239308D01*
G01X263285Y246300D02*
X249435Y232450D01*
G01X263700Y245300D02*
X249850Y231450D01*
G01X268817Y246300D02*
X263285D01*
G01X269232Y245300D02*
X263700D01*
G01X271442Y248925D02*
X268817Y246300D01*
G01X360795Y248925D02*
X271442D01*
G01X271857Y247925D02*
X269232Y245300D01*
G01X360380Y247925D02*
X271857D01*
G01X362220Y247500D02*
X360795Y248925D01*
G01X398886Y247500D02*
X362220D01*
G01X361805Y246500D02*
X360380Y247925D01*
G01X398471Y246500D02*
X361805D01*
G01X399438Y243839D02*
X399434Y245537D01*
G01X400139Y246248D02*
X398886Y247500D01*
G01X401838Y246248D02*
X400139D01*
G01X399434Y245537D02*
X398471Y246500D01*
G54D12*
G01X-31497Y-1D02*
X26377D01*
G01X-35434Y3936D02*
G03X-31497Y-1I3937J0D01*
G01X-35434Y585039D02*
Y3936D01*
G01X-7874Y588976D02*
X-31497D01*
G01D02*
G03X-35434Y585039I0J-3937D01*
G01X-12698Y15747D02*
G03I-6988J0D01*
G01Y573227D02*
G03I-6988J0D01*
G01X822835Y290551D02*
X3937D01*
G03X0Y286614I0J-3937D01*
G01Y61811D01*
G03X3937Y57874I3937J0D01*
G01X53937D01*
G02X57874Y53937I0J-3937D01*
G01Y16142D01*
X338189D01*
Y39961D01*
G02X345669I3740J0D01*
G01Y16142D01*
X389764D01*
Y42126D01*
G02X393701Y46063I3937J0D01*
G01X409449D01*
G02X413386Y42126I0J-3937D01*
G01Y3937D01*
G03X417323Y0I3937J0D01*
G01X822835D01*
G03X826772Y3937I0J3937D01*
G01Y286614D01*
G03X822835Y290551I-3937J0D01*
G01X826773Y286614D02*
G03X822836Y290551I-3937J0D01*
G01X3938D01*
G03X1Y286614I0J-3937D01*
G01Y61811D01*
G03X3938Y57874I3937J0D01*
G01X53938D01*
G02X57875Y53937I0J-3937D01*
G01Y12598D01*
X59844Y10629D01*
X336222D01*
X338190Y12598D01*
Y39960D01*
G02X345671I3740J0D01*
G01Y12598D01*
X347639Y10629D01*
X387797D01*
X389765Y12598D01*
Y42126D01*
G02X393702Y46063I3937J0D01*
G01X409450D01*
G02X413387Y42126I0J-3937D01*
G01Y3937D01*
G03X417324Y0I3937J0D01*
G01X822836D01*
G03X826773Y3937I0J3937D01*
G01Y286614D01*
G01D02*
G03X822836Y290551I-3937J0D01*
G01X3938D01*
G03X1Y286614I0J-3937D01*
G01Y61811D01*
G03X3938Y57874I3937J0D01*
G01X53938D01*
G02X57875Y53937I0J-3937D01*
G01Y12598D01*
X59844Y10629D01*
X336222D01*
X338190Y12598D01*
Y39960D01*
G02X345671I3740J0D01*
G01Y12598D01*
X347639Y10629D01*
X387797D01*
X389765Y12598D01*
Y42126D01*
G02X393702Y46063I3937J0D01*
G01X409450D01*
G02X413387Y42126I0J-3937D01*
G01Y3937D01*
G03X417324Y0I3937J0D01*
G01X822836D01*
G03X826773Y3937I0J3937D01*
G01Y286614D01*
G01X22440Y49999D02*
X-3937D01*
G01X-7874Y53936D02*
Y72440D01*
G01Y53936D02*
G03X-3937Y49999I3937J0D01*
G01X0Y72440D02*
G03X-7874I-3937J0D01*
G01Y103149D02*
G03X0I3937J0D01*
G01X-7874D02*
Y210235D01*
G01X0D02*
G03X-7874I-3937J0D01*
G01Y240944D02*
Y348031D01*
G01Y240944D02*
G03X0I3937J0D01*
G01X-3Y302361D02*
G03X3934Y298424I3937J0D01*
G01X822832D01*
G03X826769Y302361I0J3937D01*
G01Y527164D01*
G03X822832Y531101I-3937J0D01*
G01X772832D01*
G02X768895Y535038I0J3937D01*
G01Y576377D01*
X766926Y578346D01*
X490548D01*
X488580Y576377D01*
Y549015D01*
G02X481099I-3740J0D01*
G01Y576377D01*
X479131Y578346D01*
X438973D01*
X437005Y576377D01*
Y546849D01*
G02X433068Y542912I-3937J0D01*
G01X417320D01*
G02X413383Y546849I0J3937D01*
G01Y585038D01*
G03X409446Y588975I-3937J0D01*
G01X3934D01*
G03X-3Y585038I0J-3937D01*
G01Y302361D01*
G01X0Y348031D02*
G03X-7874I-3937J0D01*
G01Y378739D02*
Y485826D01*
G01Y378739D02*
G03X0I3937J0D01*
G01Y485826D02*
G03X-7874I-3937J0D01*
G01Y516535D02*
Y588976D01*
G01Y516535D02*
G03X0I3937J-1D01*
G01X17137Y687650D02*
Y675650D01*
G01X14837Y687650D02*
X19437D01*
G01X21437Y675650D02*
Y687650D01*
G01Y681850D02*
X21937Y682850D01*
X22437Y683450D01*
X23237Y683650D01*
X23837Y683450D01*
X24537Y682650D01*
X24837Y681450D01*
Y675650D01*
G01X29137Y683650D02*
Y675650D01*
G01Y686850D02*
X28937Y687050D01*
Y687450D01*
X29137Y687650D01*
X29337Y687450D01*
Y687050D01*
X29137Y686850D01*
G01X33637Y677050D02*
X34137Y676250D01*
X34837Y675650D01*
X35437D01*
X36037Y676050D01*
X36437Y676650D01*
X36637Y677450D01*
X36537Y678650D01*
X36137Y679250D01*
X34337Y680450D01*
X33937Y681850D01*
X34137Y682850D01*
X34537Y683450D01*
X35137Y683650D01*
X35737Y683450D01*
X36337Y682850D01*
G01X45737Y672650D02*
X46437Y671850D01*
X47237Y671650D01*
X47937Y671850D01*
X48537Y672850D01*
X48937Y674250D01*
Y683650D01*
G01Y682050D02*
X48537Y682850D01*
X47937Y683450D01*
X47237Y683650D01*
X46437Y683250D01*
X45937Y682450D01*
X45537Y681050D01*
X45337Y679650D01*
X45437Y678450D01*
X45837Y677050D01*
X46437Y676050D01*
X47237Y675650D01*
X47837Y675850D01*
X48537Y676650D01*
X48937Y677450D01*
G01X51637Y681050D02*
X54837D01*
X54537Y682450D01*
X54037Y683250D01*
X53337Y683650D01*
X52637Y683450D01*
X52037Y682850D01*
X51637Y681450D01*
X51437Y680250D01*
Y679050D01*
X51637Y677850D01*
X52137Y676650D01*
X52737Y675850D01*
X53437Y675650D01*
X54137Y676050D01*
X54837Y677250D01*
G01X57737Y675650D02*
Y683650D01*
G01Y682050D02*
X58237Y682850D01*
X58737Y683450D01*
X59437Y683650D01*
X59937Y683450D01*
X60537Y682850D01*
G01X63337Y675650D02*
Y687650D01*
G01Y681650D02*
X63837Y682850D01*
X64437Y683450D01*
X65037Y683650D01*
X65937Y683250D01*
X66537Y682450D01*
X66937Y681050D01*
Y679450D01*
X66737Y677850D01*
X66337Y676650D01*
X65637Y675850D01*
X65037Y675650D01*
X64437Y675850D01*
X63837Y676450D01*
X63337Y677450D01*
G01X69637Y681050D02*
X72837D01*
X72537Y682450D01*
X72037Y683250D01*
X71337Y683650D01*
X70637Y683450D01*
X70037Y682850D01*
X69637Y681450D01*
X69437Y680250D01*
Y679050D01*
X69637Y677850D01*
X70137Y676650D01*
X70737Y675850D01*
X71437Y675650D01*
X72137Y676050D01*
X72837Y677250D01*
G01X75737Y675650D02*
Y683650D01*
G01Y682050D02*
X76237Y682850D01*
X76737Y683450D01*
X77437Y683650D01*
X77937Y683450D01*
X78537Y682850D01*
G01X89137Y683650D02*
Y675650D01*
G01Y686850D02*
X88937Y687050D01*
Y687450D01*
X89137Y687650D01*
X89337Y687450D01*
Y687050D01*
X89137Y686850D01*
G01X93637Y677050D02*
X94137Y676250D01*
X94837Y675650D01*
X95437D01*
X96037Y676050D01*
X96437Y676650D01*
X96637Y677450D01*
X96537Y678650D01*
X96137Y679250D01*
X94337Y680450D01*
X93937Y681850D01*
X94137Y682850D01*
X94537Y683450D01*
X95137Y683650D01*
X95737Y683450D01*
X96337Y682850D01*
G01X105537Y672650D02*
X106237Y671850D01*
X106837Y671650D01*
X107637Y672050D01*
X108237Y673050D01*
X108537Y674850D01*
Y683650D01*
G01Y686850D02*
X108337Y687050D01*
Y687450D01*
X108537Y687650D01*
X108737Y687450D01*
Y687050D01*
X108537Y686850D01*
G01X111437Y683650D02*
Y678050D01*
X111837Y676650D01*
X112437Y675850D01*
X113137Y675650D01*
X113837Y675850D01*
X114437Y676650D01*
X114837Y678050D01*
G01Y675650D02*
Y683650D01*
G01X117637Y677050D02*
X118137Y676250D01*
X118837Y675650D01*
X119437D01*
X120037Y676050D01*
X120437Y676650D01*
X120637Y677450D01*
X120537Y678650D01*
X120137Y679250D01*
X118337Y680450D01*
X117937Y681850D01*
X118137Y682850D01*
X118537Y683450D01*
X119137Y683650D01*
X119737Y683450D01*
X120337Y682850D01*
G01X125137Y687650D02*
Y675650D01*
G01X123737Y683650D02*
X126537D01*
G01X136537Y675650D02*
Y685850D01*
X136737Y686850D01*
X137137Y687450D01*
X137737Y687650D01*
X138337Y687250D01*
X138637Y686250D01*
G01X137437Y682850D02*
X135437D01*
G01X143137Y675650D02*
X142537Y675850D01*
X141937Y676650D01*
X141537Y678050D01*
X141337Y679650D01*
X141537Y681250D01*
X141937Y682650D01*
X142537Y683450D01*
X143137Y683650D01*
X143737Y683450D01*
X144337Y682650D01*
X144737Y681250D01*
X144837Y679650D01*
X144737Y678050D01*
X144337Y676650D01*
X143737Y675850D01*
X143137Y675650D01*
G01X147737D02*
Y683650D01*
G01Y682050D02*
X148237Y682850D01*
X148737Y683450D01*
X149437Y683650D01*
X149937Y683450D01*
X150537Y682850D01*
G01X159037Y672050D02*
X159637Y671650D01*
X160437Y672050D01*
X160937Y672850D01*
X161337Y673850D01*
X161937Y677050D01*
X163237Y683650D01*
G01X160037D02*
X161937Y677050D01*
G01X167137Y675650D02*
X166537Y675850D01*
X165937Y676650D01*
X165537Y678050D01*
X165337Y679650D01*
X165537Y681250D01*
X165937Y682650D01*
X166537Y683450D01*
X167137Y683650D01*
X167737Y683450D01*
X168337Y682650D01*
X168737Y681250D01*
X168837Y679650D01*
X168737Y678050D01*
X168337Y676650D01*
X167737Y675850D01*
X167137Y675650D01*
G01X171437Y683650D02*
Y678050D01*
X171837Y676650D01*
X172437Y675850D01*
X173137Y675650D01*
X173837Y675850D01*
X174437Y676650D01*
X174837Y678050D01*
G01Y675650D02*
Y683650D01*
G01X183737Y675650D02*
Y683650D01*
G01Y682050D02*
X184237Y682850D01*
X184737Y683450D01*
X185437Y683650D01*
X185937Y683450D01*
X186537Y682850D01*
G01X189637Y681050D02*
X192837D01*
X192537Y682450D01*
X192037Y683250D01*
X191337Y683650D01*
X190637Y683450D01*
X190037Y682850D01*
X189637Y681450D01*
X189437Y680250D01*
Y679050D01*
X189637Y677850D01*
X190137Y676650D01*
X190737Y675850D01*
X191437Y675650D01*
X192137Y676050D01*
X192837Y677250D01*
G01X196537Y675650D02*
Y685850D01*
X196737Y686850D01*
X197137Y687450D01*
X197737Y687650D01*
X198337Y687250D01*
X198637Y686250D01*
G01X197437Y682850D02*
X195437D01*
G01X201637Y681050D02*
X204837D01*
X204537Y682450D01*
X204037Y683250D01*
X203337Y683650D01*
X202637Y683450D01*
X202037Y682850D01*
X201637Y681450D01*
X201437Y680250D01*
Y679050D01*
X201637Y677850D01*
X202137Y676650D01*
X202737Y675850D01*
X203437Y675650D01*
X204137Y676050D01*
X204837Y677250D01*
G01X207737Y675650D02*
Y683650D01*
G01Y682050D02*
X208237Y682850D01*
X208737Y683450D01*
X209437Y683650D01*
X209937Y683450D01*
X210537Y682850D01*
G01X213637Y681050D02*
X216837D01*
X216537Y682450D01*
X216037Y683250D01*
X215337Y683650D01*
X214637Y683450D01*
X214037Y682850D01*
X213637Y681450D01*
X213437Y680250D01*
Y679050D01*
X213637Y677850D01*
X214137Y676650D01*
X214737Y675850D01*
X215437Y675650D01*
X216137Y676050D01*
X216837Y677250D01*
G01X219437Y675650D02*
Y683650D01*
G01Y681650D02*
X219837Y682650D01*
X220437Y683450D01*
X221237Y683650D01*
X221937Y683450D01*
X222537Y682650D01*
X222837Y681250D01*
Y675650D01*
G01X228737Y682650D02*
X228037Y683450D01*
X227437Y683650D01*
X226637Y683250D01*
X226037Y682450D01*
X225637Y681050D01*
X225537Y679650D01*
X225637Y678250D01*
X226037Y677050D01*
X226637Y676050D01*
X227437Y675650D01*
X228137Y676050D01*
X228737Y676850D01*
G01X231637Y681050D02*
X234837D01*
X234537Y682450D01*
X234037Y683250D01*
X233337Y683650D01*
X232637Y683450D01*
X232037Y682850D01*
X231637Y681450D01*
X231437Y680250D01*
Y679050D01*
X231637Y677850D01*
X232137Y676650D01*
X232737Y675850D01*
X233437Y675650D01*
X234137Y676050D01*
X234837Y677250D01*
G01X245137Y687650D02*
Y675650D01*
G01X243737Y683650D02*
X246537D01*
G01X251137Y675650D02*
X250537Y675850D01*
X249937Y676650D01*
X249537Y678050D01*
X249337Y679650D01*
X249537Y681250D01*
X249937Y682650D01*
X250537Y683450D01*
X251137Y683650D01*
X251737Y683450D01*
X252337Y682650D01*
X252737Y681250D01*
X252837Y679650D01*
X252737Y678050D01*
X252337Y676650D01*
X251737Y675850D01*
X251137Y675650D01*
G01X262537D02*
Y685850D01*
X262737Y686850D01*
X263137Y687450D01*
X263737Y687650D01*
X264337Y687250D01*
X264637Y686250D01*
G01X263437Y682850D02*
X261437D01*
G01X269137Y683650D02*
Y675650D01*
G01Y686850D02*
X268937Y687050D01*
Y687450D01*
X269137Y687650D01*
X269337Y687450D01*
Y687050D01*
X269137Y686850D01*
G01X273437Y675650D02*
Y683650D01*
G01Y681650D02*
X273837Y682650D01*
X274437Y683450D01*
X275237Y683650D01*
X275937Y683450D01*
X276537Y682650D01*
X276837Y681250D01*
Y675650D01*
G01X282937Y687650D02*
Y675650D01*
G01Y677450D02*
X282537Y676450D01*
X281937Y675850D01*
X281237Y675650D01*
X280437Y676050D01*
X279837Y677050D01*
X279437Y678250D01*
X279337Y679650D01*
X279437Y681050D01*
X279837Y682250D01*
X280437Y683250D01*
X281237Y683650D01*
X281937Y683450D01*
X282437Y683050D01*
X282937Y682250D01*
G01X293137Y687650D02*
Y675650D01*
G01X291737Y683650D02*
X294537D01*
G01X297437Y675650D02*
Y687650D01*
G01Y681850D02*
X297937Y682850D01*
X298437Y683450D01*
X299237Y683650D01*
X299837Y683450D01*
X300537Y682650D01*
X300837Y681450D01*
Y675650D01*
G01X303637Y681050D02*
X306837D01*
X306537Y682450D01*
X306037Y683250D01*
X305337Y683650D01*
X304637Y683450D01*
X304037Y682850D01*
X303637Y681450D01*
X303437Y680250D01*
Y679050D01*
X303637Y677850D01*
X304137Y676650D01*
X304737Y675850D01*
X305437Y675650D01*
X306137Y676050D01*
X306837Y677250D01*
G01X318937Y687650D02*
Y675650D01*
G01Y677450D02*
X318537Y676450D01*
X317937Y675850D01*
X317237Y675650D01*
X316437Y676050D01*
X315837Y677050D01*
X315437Y678250D01*
X315337Y679650D01*
X315437Y681050D01*
X315837Y682250D01*
X316437Y683250D01*
X317237Y683650D01*
X317937Y683450D01*
X318437Y683050D01*
X318937Y682250D01*
G01X323137Y683650D02*
Y675650D01*
G01Y686850D02*
X322937Y687050D01*
Y687450D01*
X323137Y687650D01*
X323337Y687450D01*
Y687050D01*
X323137Y686850D01*
G01X328537Y675650D02*
Y685850D01*
X328737Y686850D01*
X329137Y687450D01*
X329737Y687650D01*
X330337Y687250D01*
X330637Y686250D01*
G01X329437Y682850D02*
X327437D01*
G01X334537Y675650D02*
Y685850D01*
X334737Y686850D01*
X335137Y687450D01*
X335737Y687650D01*
X336337Y687250D01*
X336637Y686250D01*
G01X335437Y682850D02*
X333437D01*
G01X339637Y681050D02*
X342837D01*
X342537Y682450D01*
X342037Y683250D01*
X341337Y683650D01*
X340637Y683450D01*
X340037Y682850D01*
X339637Y681450D01*
X339437Y680250D01*
Y679050D01*
X339637Y677850D01*
X340137Y676650D01*
X340737Y675850D01*
X341437Y675650D01*
X342137Y676050D01*
X342837Y677250D01*
G01X345737Y675650D02*
Y683650D01*
G01Y682050D02*
X346237Y682850D01*
X346737Y683450D01*
X347437Y683650D01*
X347937Y683450D01*
X348537Y682850D01*
G01X351637Y681050D02*
X354837D01*
X354537Y682450D01*
X354037Y683250D01*
X353337Y683650D01*
X352637Y683450D01*
X352037Y682850D01*
X351637Y681450D01*
X351437Y680250D01*
Y679050D01*
X351637Y677850D01*
X352137Y676650D01*
X352737Y675850D01*
X353437Y675650D01*
X354137Y676050D01*
X354837Y677250D01*
G01X357437Y675650D02*
Y683650D01*
G01Y681650D02*
X357837Y682650D01*
X358437Y683450D01*
X359237Y683650D01*
X359937Y683450D01*
X360537Y682650D01*
X360837Y681250D01*
Y675650D01*
G01X365137Y687650D02*
Y675650D01*
G01X363737Y683650D02*
X366537D01*
G01X371137D02*
Y675650D01*
G01Y686850D02*
X370937Y687050D01*
Y687450D01*
X371137Y687650D01*
X371337Y687450D01*
Y687050D01*
X371137Y686850D01*
G01X378937Y675650D02*
Y683650D01*
G01Y682250D02*
X378537Y683050D01*
X377937Y683450D01*
X377237Y683650D01*
X376537Y683250D01*
X375937Y682450D01*
X375537Y681250D01*
X375337Y679650D01*
X375537Y678050D01*
X375937Y676850D01*
X376537Y676050D01*
X377237Y675650D01*
X377937Y675850D01*
X378537Y676450D01*
X378937Y677250D01*
G01X383137Y675650D02*
Y687650D01*
G01X395137D02*
Y675650D01*
G01X393737Y683650D02*
X396537D01*
G01X399737Y675650D02*
Y683650D01*
G01Y682050D02*
X400237Y682850D01*
X400737Y683450D01*
X401437Y683650D01*
X401937Y683450D01*
X402537Y682850D01*
G01X408937Y675650D02*
Y683650D01*
G01Y682250D02*
X408537Y683050D01*
X407937Y683450D01*
X407237Y683650D01*
X406537Y683250D01*
X405937Y682450D01*
X405537Y681250D01*
X405337Y679650D01*
X405537Y678050D01*
X405937Y676850D01*
X406537Y676050D01*
X407237Y675650D01*
X407937Y675850D01*
X408537Y676450D01*
X408937Y677250D01*
G01X414737Y682650D02*
X414037Y683450D01*
X413437Y683650D01*
X412637Y683250D01*
X412037Y682450D01*
X411637Y681050D01*
X411537Y679650D01*
X411637Y678250D01*
X412037Y677050D01*
X412637Y676050D01*
X413437Y675650D01*
X414137Y676050D01*
X414737Y676850D01*
G01X417637Y681050D02*
X420837D01*
X420537Y682450D01*
X420037Y683250D01*
X419337Y683650D01*
X418637Y683450D01*
X418037Y682850D01*
X417637Y681450D01*
X417437Y680250D01*
Y679050D01*
X417637Y677850D01*
X418137Y676650D01*
X418737Y675850D01*
X419437Y675650D01*
X420137Y676050D01*
X420837Y677250D01*
G01X423637Y677050D02*
X424137Y676250D01*
X424837Y675650D01*
X425437D01*
X426037Y676050D01*
X426437Y676650D01*
X426637Y677450D01*
X426537Y678650D01*
X426137Y679250D01*
X424337Y680450D01*
X423937Y681850D01*
X424137Y682850D01*
X424537Y683450D01*
X425137Y683650D01*
X425737Y683450D01*
X426337Y682850D01*
G01X437137Y683650D02*
Y675650D01*
G01Y686850D02*
X436937Y687050D01*
Y687450D01*
X437137Y687650D01*
X437337Y687450D01*
Y687050D01*
X437137Y686850D01*
G01X441437Y675650D02*
Y683650D01*
G01Y681650D02*
X441837Y682650D01*
X442437Y683450D01*
X443237Y683650D01*
X443937Y683450D01*
X444537Y682650D01*
X444837Y681250D01*
Y675650D01*
G01X455137D02*
Y687650D01*
G01X462937Y675650D02*
Y683650D01*
G01Y682250D02*
X462537Y683050D01*
X461937Y683450D01*
X461237Y683650D01*
X460537Y683250D01*
X459937Y682450D01*
X459537Y681250D01*
X459337Y679650D01*
X459537Y678050D01*
X459937Y676850D01*
X460537Y676050D01*
X461237Y675650D01*
X461937Y675850D01*
X462537Y676450D01*
X462937Y677250D01*
G01X465037Y672050D02*
X465637Y671650D01*
X466437Y672050D01*
X466937Y672850D01*
X467337Y673850D01*
X467937Y677050D01*
X469237Y683650D01*
G01X466037D02*
X467937Y677050D01*
G01X471637Y681050D02*
X474837D01*
X474537Y682450D01*
X474037Y683250D01*
X473337Y683650D01*
X472637Y683450D01*
X472037Y682850D01*
X471637Y681450D01*
X471437Y680250D01*
Y679050D01*
X471637Y677850D01*
X472137Y676650D01*
X472737Y675850D01*
X473437Y675650D01*
X474137Y676050D01*
X474837Y677250D01*
G01X477737Y675650D02*
Y683650D01*
G01Y682050D02*
X478237Y682850D01*
X478737Y683450D01*
X479437Y683650D01*
X479937Y683450D01*
X480537Y682850D01*
G01X489137Y687650D02*
Y675650D01*
X493137D01*
G01X497137D02*
Y687650D01*
X495937Y685250D01*
G01Y675650D02*
X498337D01*
G01X503137Y687650D02*
X502337Y687250D01*
X501737Y686250D01*
X501337Y685050D01*
X501037Y683450D01*
X500937Y681650D01*
X501037Y679850D01*
X501337Y678250D01*
X501737Y677050D01*
X502337Y676050D01*
X503137Y675650D01*
X503937Y676050D01*
X504537Y677050D01*
X504937Y678250D01*
X505237Y679850D01*
X505337Y681650D01*
X505237Y683450D01*
X504937Y685050D01*
X504537Y686250D01*
X503937Y687250D01*
X503137Y687650D01*
G01X26377Y-1D02*
Y46062D01*
G01D02*
G03X22440Y49999I-3937J0D01*
G01X102756Y290550D02*
G03Y298424I0J3937D01*
G01X133465D02*
G03Y290550I0J-3937D01*
G01X299606Y290551D02*
G03Y298425I0J3937D01*
G01X330314D02*
G03Y290551I0J-3937D01*
G01X353350Y224807D02*
X347051D01*
G02Y237406I0J6299D01*
G01X353350D01*
G02Y224807I0J-6299D01*
G01X496457Y290550D02*
G03Y298424I0J3937D01*
G01X527166D02*
G03Y290550I0J-3937D01*
G01X693308D02*
G03Y298424I0J3937D01*
G01X724016D02*
G03Y290550I0J-3937D01*
G01X800393Y588976D02*
Y542913D01*
G01D02*
G03X804330Y538976I3937J0D01*
G01X858267Y588976D02*
X800393D01*
G01X804330Y538976D02*
X830708D01*
G01X834645Y72440D02*
G03X826771I-3937J0D01*
G01Y103149D02*
G03X834645I3937J0D01*
G01Y210235D02*
G03X826771I-3937J0D01*
G01Y240944D02*
G03X834645I3937J0D01*
G01Y348031D02*
G03X826771I-3937J0D01*
G01Y378739D02*
G03X834645I3937J0D01*
G01Y485826D02*
G03X826771I-3937J0D01*
G01Y516535D02*
G03X834645I3937J-1D01*
G01Y535039D02*
G03X830708Y538976I-3937J0D01*
G01X834645Y72440D02*
Y-1D01*
G01D02*
X858267D01*
G01X853444Y15747D02*
G03I-6988J0D01*
G01X834645Y210235D02*
Y103149D01*
G01Y348031D02*
Y240944D01*
G01Y485826D02*
Y378739D01*
G01Y535039D02*
Y516535D01*
G01X853444Y573227D02*
G03I-6988J0D01*
G01X862204Y3936D02*
Y585039D01*
G01X858267Y-1D02*
G03X862204Y3936I0J3937D01*
G01Y585039D02*
G03X858267Y588976I-3937J0D01*
G01X447851Y146400D02*
X518100D01*
G01X444325Y142874D02*
X447851Y146400D01*
G01X438826Y142874D02*
X444325D01*
G01X437300Y144400D02*
X438826Y142874D01*
G01X448307Y145300D02*
X517644D01*
G01X444781Y141774D02*
X448307Y145300D01*
G01X438370Y141774D02*
X444781D01*
G01X436644Y143500D02*
X438370Y141774D01*
G01X522100Y142400D02*
X530100D01*
G01X518100Y146400D02*
X522100Y142400D01*
G01X521644Y141300D02*
X530556D01*
G01X517644Y145300D02*
X521644Y141300D01*
G01X531900Y146300D02*
X558600D01*
G01X530700Y145100D02*
X531900Y146300D01*
G01X530700Y143000D02*
Y145100D01*
G01X530100Y142400D02*
X530700Y143000D01*
G01X541026Y144710D02*
X541516Y145200D01*
G01X539226Y144710D02*
X541026D01*
G01X538736Y145200D02*
X539226Y144710D01*
G01X536936Y145200D02*
X538736D01*
G01X536446Y144710D02*
X536936Y145200D01*
G01X534646Y144710D02*
X536446D01*
G01X534156Y145200D02*
X534646Y144710D01*
G01X532356Y145200D02*
X534156D01*
G01X531800Y144644D02*
X532356Y145200D01*
G01X531800Y142544D02*
Y144644D01*
G01X530556Y141300D02*
X531800Y142544D01*
G01X546096Y145200D02*
X558144D01*
G01X545606Y144710D02*
X546096Y145200D01*
G01X543806Y144710D02*
X545606D01*
G01X543316Y145200D02*
X543806Y144710D01*
G01X541516Y145200D02*
X543316D01*
G01X566044Y146300D02*
X577500D01*
G01X564800Y145056D02*
X566044Y146300D01*
G01X564800Y143300D02*
Y145056D01*
G01X564200Y142700D02*
X564800Y143300D01*
G01X560500Y142700D02*
X564200D01*
G01X559900Y143300D02*
X560500Y142700D01*
G01X559900Y145000D02*
Y143300D01*
G01X558600Y146300D02*
X559900Y145000D01*
G01X566500Y145200D02*
X577044D01*
G01X565900Y144600D02*
X566500Y145200D01*
G01X565900Y142844D02*
Y144600D01*
G01X564656Y141600D02*
X565900Y142844D01*
G01X560044Y141600D02*
X564656D01*
G01X558800Y142844D02*
X560044Y141600D01*
G01X558800Y144544D02*
Y142844D01*
G01X558144Y145200D02*
X558800Y144544D01*
G01X587600Y142700D02*
X587900Y142400D01*
G01X580000Y142700D02*
X587600D01*
G01X579000Y143700D02*
X580000Y142700D01*
G01X579000Y144800D02*
Y143700D01*
G01X577500Y146300D02*
X579000Y144800D01*
G01X587444Y141300D02*
X600156D01*
G01X587144Y141600D02*
X587444Y141300D01*
G01X579544Y141600D02*
X587144D01*
G01X577900Y143244D02*
X579544Y141600D01*
G01X577900Y144344D02*
Y143244D01*
G01X577044Y145200D02*
X577900Y144344D01*
G01X601200Y143900D02*
X606300D01*
G01X599700Y142400D02*
X601200Y143900D01*
G01X587900Y142400D02*
X599700D01*
G01X601656Y142800D02*
X605844D01*
G01X600156Y141300D02*
X601656Y142800D01*
G01X613444Y146069D02*
X621795D01*
G01X609775Y142400D02*
X613444Y146069D01*
G01X607800Y142400D02*
X609775D01*
G01X606300Y143900D02*
X607800Y142400D01*
G01X613900Y144969D02*
X621339D01*
G01X610231Y141300D02*
X613900Y144969D01*
G01X607344Y141300D02*
X610231D01*
G01X605844Y142800D02*
X607344Y141300D01*
G01X621795Y146069D02*
X705706Y62158D01*
G01X621339Y144969D02*
X704606Y61702D01*
G01Y48894D02*
X714100Y39400D01*
G01X705706Y49350D02*
X715200Y39856D01*
G01X705706Y62158D02*
Y49350D01*
G01X704606Y61702D02*
Y48894D01*
G01X717282Y24000D02*
X718375Y22907D01*
G01X717282Y25681D02*
Y24000D01*
G01X715200Y27763D02*
X717282Y25681D01*
G01X715200Y39856D02*
Y27763D01*
G01X716182Y23999D02*
X715090Y22907D01*
G01X716182Y25225D02*
Y23999D01*
G01X714100Y27307D02*
X716182Y25225D01*
G01X714100Y39400D02*
Y27307D01*
G54D13*
G01X78871Y43000D02*
X79771Y43900D01*
G01X78871Y41517D02*
Y43000D01*
G01X80031Y40357D02*
X78871Y41517D01*
G01X77571D02*
X76411Y40357D01*
G01X77571Y43539D02*
Y41517D01*
G01X79232Y45200D02*
X77571Y43539D01*
G01X89310Y43900D02*
X92800Y47390D01*
G01X93218Y41416D02*
X92159Y40357D01*
G01X93218Y43357D02*
Y41416D01*
G01X95911Y46050D02*
X93218Y43357D01*
G01X92800Y52600D02*
X100900Y60700D01*
G01X92800Y47390D02*
Y52600D01*
G01X79771Y43900D02*
X89310D01*
G01X88771Y45200D02*
X79232D01*
G01X91500Y47929D02*
X88771Y45200D01*
G01X91500Y53139D02*
Y47929D01*
G01X99600Y61239D02*
X91500Y53139D01*
G01X109067Y41517D02*
X107907Y40357D01*
G01X109067Y49906D02*
Y41517D01*
G01X94518Y41618D02*
X95779Y40357D01*
G01X94518Y42818D02*
Y41618D01*
G01X96450Y44750D02*
X94518Y42818D01*
G01X111600Y52439D02*
X109067Y49906D01*
G01X104400Y44750D02*
X96450D01*
G01X106530Y46880D02*
X104400Y44750D01*
G01X106530Y52291D02*
Y46880D01*
G01X107600Y53361D02*
X106530Y52291D01*
G01X107600Y59739D02*
Y53361D01*
G01X103861Y46050D02*
X95911D01*
G01X105230Y47419D02*
X103861Y46050D01*
G01X105230Y52830D02*
Y47419D01*
G01X106300Y53900D02*
X105230Y52830D01*
G01X106300Y59200D02*
Y53900D01*
G01X105400Y60100D02*
X106300Y59200D01*
G01X100900Y69004D02*
X126470Y94574D01*
G01X100900Y60700D02*
Y69004D01*
G01X99600Y69543D02*
Y61239D01*
G01X125170Y95113D02*
X99600Y69543D01*
G01X106700Y60639D02*
X107600Y59739D01*
G01X106700Y69500D02*
Y60639D01*
G01X130221Y93021D02*
X106700Y69500D01*
G01X105400Y70039D02*
Y60100D01*
G01X128921Y93560D02*
X105400Y70039D01*
G01X110367Y41517D02*
X111527Y40357D01*
G01X110367Y44415D02*
Y41517D01*
G01X124815D02*
X123655Y40357D01*
G01X124815Y62760D02*
Y41517D01*
G01X111207Y45255D02*
X110367Y44415D01*
G01X111207Y46605D02*
Y45255D01*
G01X110367Y47445D02*
X111207Y46605D01*
G01X110367Y49367D02*
Y47445D01*
G01X112900Y51900D02*
X110367Y49367D01*
G01X112900Y61400D02*
Y51900D01*
G01X111600Y61939D02*
Y52439D01*
G01X114100Y62600D02*
X112900Y61400D01*
G01X117320Y62600D02*
X114100D01*
G01X148413Y93693D02*
X117320Y62600D01*
G01X113561Y63900D02*
X111600Y61939D01*
G01X116781Y63900D02*
X113561D01*
G01X147113Y94232D02*
X116781Y63900D01*
G01X128155Y66100D02*
X124815Y62760D01*
G01X125170Y98874D02*
Y95113D01*
G01X128800Y102504D02*
X125170Y98874D01*
G01X140563Y41517D02*
X139403Y40357D01*
G01X140563Y56392D02*
Y41517D01*
G01X126115D02*
X127275Y40357D01*
G01X126115Y62221D02*
Y41517D01*
G01X141750Y57579D02*
X140563Y56392D01*
G01X128694Y64800D02*
X126115Y62221D01*
G01X130140Y64800D02*
X128694D01*
G01X152440Y87100D02*
X130140Y64800D01*
G01X129601Y66100D02*
X128155D01*
G01X151901Y88400D02*
X129601Y66100D01*
G01X130100Y101965D02*
Y114261D01*
G01X126470Y98335D02*
X130100Y101965D01*
G01X126470Y94574D02*
Y98335D01*
G01X128800Y114800D02*
Y102504D01*
G01X130221Y96782D02*
Y93021D01*
G01X133900Y100461D02*
X130221Y96782D01*
G01X133900Y112757D02*
Y100461D01*
G01X128921Y97321D02*
Y93560D01*
G01X132600Y101000D02*
X128921Y97321D01*
G01X132600Y113296D02*
Y101000D01*
G01X130100Y114261D02*
X171839Y156000D01*
G01X171300Y157300D02*
X128800Y114800D01*
G01X173343Y152200D02*
X133900Y112757D01*
G01X172804Y153500D02*
X132600Y113296D01*
G01X141863Y41517D02*
X143023Y40357D01*
G01X141863Y55853D02*
Y41517D01*
G01X156311D02*
X155151Y40357D01*
G01X152100Y46900D02*
X156311Y42689D01*
G01X143050Y57040D02*
X141863Y55853D01*
G01X143050Y60893D02*
Y57040D01*
G01X141750Y61432D02*
Y57579D01*
G01X153400Y47439D02*
X157611Y43228D01*
G01X153400Y49861D02*
Y47439D01*
G01X154619Y51080D02*
X153400Y49861D01*
G01X156180Y51080D02*
X154619D01*
G01X152100Y50400D02*
Y46900D01*
G01X154080Y52380D02*
X152100Y50400D01*
G01X155641Y52380D02*
X154080D01*
G01X162511Y59250D02*
X155641Y52380D01*
G01X145313Y63156D02*
X143050Y60893D01*
G01X146587Y63156D02*
X145313D01*
G01X149950Y66519D02*
X146587Y63156D01*
G01X149950Y67651D02*
Y66519D01*
G01X170180Y87881D02*
X149950Y67651D01*
G01X144774Y64456D02*
X141750Y61432D01*
G01X146048Y64456D02*
X144774D01*
G01X148650Y67058D02*
X146048Y64456D01*
G01X148650Y68190D02*
Y67058D01*
G01X168880Y88420D02*
X148650Y68190D01*
G01X154250Y87100D02*
X152440D01*
G01X162100Y94950D02*
X154250Y87100D01*
G01X153711Y88400D02*
X151901D01*
G01X160800Y95489D02*
X153711Y88400D01*
G01X148413Y104213D02*
Y93693D01*
G01X154600Y110400D02*
X148413Y104213D01*
G01X147113Y104752D02*
Y94232D01*
G01X153300Y110939D02*
X147113Y104752D01*
G01X154600Y119400D02*
Y110400D01*
G01X175000Y139800D02*
X154600Y119400D01*
G01X153300Y119939D02*
Y110939D01*
G01X174461Y141100D02*
X153300Y119939D01*
G01X157611Y41517D02*
X158771Y40357D01*
G01X157611Y43228D02*
Y41517D01*
G01X156311Y42689D02*
Y41517D01*
G01X172059D02*
X170899Y40357D01*
G01X163050Y57950D02*
X156180Y51080D01*
G01X177450Y57950D02*
X163050D01*
G01X176911Y59250D02*
X162511D01*
G01X170180Y96880D02*
Y87881D01*
G01X168880Y97419D02*
Y88420D01*
G01X177775Y104475D02*
X170180Y96880D01*
G01X176475Y105014D02*
X168880Y97419D01*
G01X162100Y107137D02*
Y94950D01*
G01X160800Y107676D02*
Y95489D01*
G01X181200Y126237D02*
X162100Y107137D01*
G01X179900Y126776D02*
X160800Y107676D01*
G01X191157Y157300D02*
X171300D01*
G01X173359Y41517D02*
X174519Y40357D01*
G01X173359Y42760D02*
Y41517D01*
G01X175377Y44778D02*
X173359Y42760D01*
G01X172059Y43299D02*
Y41517D01*
G01X174838Y46078D02*
X172059Y43299D01*
G01X187700Y41410D02*
X186647Y40357D01*
G01X186700Y67200D02*
X177450Y57950D01*
G01X185400Y67739D02*
X176911Y59250D01*
G01X179838Y44778D02*
X175377D01*
G01X180678Y43938D02*
X179838Y44778D01*
G01X182028Y43938D02*
X180678D01*
G01X182868Y44778D02*
X182028Y43938D01*
G01X185317Y44778D02*
X182868D01*
G01X189339Y48800D02*
X185317Y44778D01*
G01X184778Y46078D02*
X174838D01*
G01X188800Y50100D02*
X184778Y46078D01*
G01X186700Y69100D02*
Y67200D01*
G01X190200Y72600D02*
X186700Y69100D01*
G01X185400Y69639D02*
Y67739D01*
G01X188900Y73139D02*
X185400Y69639D01*
G01X177775Y110275D02*
Y104475D01*
G01X176475Y110814D02*
Y105014D01*
G01X197500Y130000D02*
X177775Y110275D01*
G01X196961Y131300D02*
X176475Y110814D01*
G01X181200Y132961D02*
Y126237D01*
G01X186239Y138000D02*
X181200Y132961D01*
G01X179900Y133500D02*
Y126776D01*
G01X185700Y139300D02*
X179900Y133500D01*
G01X182735Y139800D02*
X175000D01*
G01X184685Y141750D02*
X182735Y139800D01*
G01X191409Y141750D02*
X184685D01*
G01X182196Y141100D02*
X174461D01*
G01X184146Y143050D02*
X182196Y141100D01*
G01X190870Y143050D02*
X184146D01*
G01X192963Y138000D02*
X186239D01*
G01X192424Y139300D02*
X185700D01*
G01X171839Y156000D02*
X191696D01*
G01X193200Y152200D02*
X173343D01*
G01X192661Y153500D02*
X172804D01*
G01X189000Y41624D02*
X190267Y40357D01*
G01X189000Y42361D02*
Y41624D01*
G01X189685Y43046D02*
X189000Y42361D01*
G01X205185Y43046D02*
X189685D01*
G01X187700Y42900D02*
Y41410D01*
G01X189146Y44346D02*
X187700Y42900D01*
G01X208050Y48800D02*
X189339D01*
G01X207511Y50100D02*
X188800D01*
G01X204646Y44346D02*
X189146D01*
G01X190200Y83361D02*
Y72600D01*
G01X188900Y83900D02*
Y73139D01*
G01X199300Y92461D02*
X190200Y83361D01*
G01X198000Y93000D02*
X188900Y83900D01*
G01X199300Y101461D02*
Y92461D01*
G01X207339Y109500D02*
X199300Y101461D01*
G01X198000Y102000D02*
Y93000D01*
G01X206800Y110800D02*
X198000Y102000D01*
G01X210000Y130000D02*
X197500D01*
G01X209461Y131300D02*
X196961D01*
G01X199359Y149700D02*
X191409Y141750D01*
G01X201925Y149700D02*
X199359D01*
G01X210050Y157825D02*
X201925Y149700D01*
G01X198820Y151000D02*
X190870Y143050D01*
G01X201386Y151000D02*
X198820D01*
G01X208750Y158364D02*
X201386Y151000D01*
G01X200913Y145950D02*
X192963Y138000D01*
G01X206748Y145950D02*
X200913D01*
G01X200374Y147250D02*
X192424Y139300D01*
G01X206209Y147250D02*
X200374D01*
G01X197078Y161382D02*
Y176239D01*
G01X191696Y156000D02*
X197078Y161382D01*
G01X195778Y161921D02*
X191157Y157300D01*
G01X195778Y176778D02*
Y161921D01*
G01X197200Y156200D02*
X193200Y152200D01*
G01X202700Y156200D02*
X197200D01*
G01X196661Y157500D02*
X192661Y153500D01*
G01X202161Y157500D02*
X196661D01*
G01X205000Y160339D02*
X202161Y157500D01*
G01X201039Y180200D02*
X206314D01*
G01X197078Y176239D02*
X201039Y180200D01*
G01X200500Y181500D02*
X195778Y176778D01*
G01X205775Y181500D02*
X200500D01*
G01X192275Y194414D02*
X196161Y198300D01*
G01X192275Y191386D02*
Y194414D01*
G01X194939Y188722D02*
X192275Y191386D01*
G01X198266Y188722D02*
X194939D01*
G01X199441Y187547D02*
X198266Y188722D01*
G01X198467Y190022D02*
X199392Y190947D01*
G01X195478Y190022D02*
X198467D01*
G01X193575Y191925D02*
X195478Y190022D01*
G01X193575Y193875D02*
Y191925D01*
G01X196700Y197000D02*
X193575Y193875D01*
G01X205500Y197000D02*
X196700D01*
G01X196161Y198300D02*
X204961D01*
G01X207189Y45050D02*
X205185Y43046D01*
G01X212900Y42361D02*
Y44161D01*
G01X214561Y40700D02*
X212900Y42361D01*
G01X218900Y40700D02*
X214561D01*
G01X214200Y42900D02*
Y44700D01*
G01X215100Y42000D02*
X214200Y42900D01*
G01X218361Y42000D02*
X215100D01*
G01X214050Y54800D02*
X208050Y48800D01*
G01X214050Y64589D02*
Y54800D01*
G01X212750Y55339D02*
X207511Y50100D01*
G01X212750Y64050D02*
Y55339D01*
G01X212011Y45050D02*
X207189D01*
G01X212900Y44161D02*
X212011Y45050D01*
G01X206650Y46350D02*
X204646Y44346D01*
G01X212550Y46350D02*
X206650D01*
G01X214200Y44700D02*
X212550Y46350D01*
G01X216600Y51265D02*
X218532Y49332D01*
G01X216600Y66139D02*
Y51265D01*
G01X209000Y69639D02*
X214050Y64589D01*
G01X209000Y97661D02*
Y69639D01*
G01X207700Y69100D02*
X212750Y64050D01*
G01X207700Y98200D02*
Y69100D01*
G01X218500Y68039D02*
X216600Y66139D01*
G01X220650Y109311D02*
X209000Y97661D01*
G01X219350Y109850D02*
X207700Y98200D01*
G01X209839Y109500D02*
X207339D01*
G01X212730Y112391D02*
X209839Y109500D01*
G01X212730Y118730D02*
Y112391D01*
G01X220675Y126675D02*
X212730Y118730D01*
G01X209300Y110800D02*
X206800D01*
G01X211430Y112930D02*
X209300Y110800D01*
G01X211430Y119269D02*
Y112930D01*
G01X219375Y127214D02*
X211430Y119269D01*
G01X213725Y133725D02*
X210000Y130000D01*
G01X213725Y139956D02*
Y133725D01*
G01X212425Y134264D02*
X209461Y131300D01*
G01X212425Y140495D02*
Y134264D01*
G01X221427Y147658D02*
X213725Y139956D01*
G01X220127Y148197D02*
X212425Y140495D01*
G01X217102Y156304D02*
X206748Y145950D01*
G01X215802Y156843D02*
X206209Y147250D01*
G01X210050Y171596D02*
Y157825D01*
G01X208750Y172135D02*
Y158364D01*
G01X217102Y173344D02*
Y156304D01*
G01X215802Y173883D02*
Y156843D01*
G01X206300Y159800D02*
X202700Y156200D01*
G01X206300Y174882D02*
Y159800D01*
G01X205000Y175421D02*
Y160339D01*
G01X218625Y180171D02*
X210050Y171596D01*
G01X217325Y180710D02*
X208750Y172135D01*
G01X217325Y188100D02*
Y180710D01*
G01X222375Y178617D02*
X217102Y173344D01*
G01X221075Y179156D02*
X215802Y173883D01*
G01X206314Y180200D02*
X211125Y185011D01*
G01X209825Y185550D02*
X205775Y181500D01*
G01X214875Y183457D02*
X206300Y174882D01*
G01X213575Y183996D02*
X205000Y175421D01*
G01X231150Y201925D02*
X217325Y188100D01*
G01X216694Y196275D02*
X244344Y223925D01*
G01X214593Y196275D02*
X216694D01*
G01X211125Y192807D02*
X214593Y196275D01*
G01X211125Y185011D02*
Y192807D01*
G01X209825Y193346D02*
Y185550D01*
G01X214054Y197575D02*
X209825Y193346D01*
G01X216155Y197575D02*
X214054D01*
G01X243805Y225225D02*
X216155Y197575D01*
G01X214875Y189147D02*
Y183457D01*
G01X245903Y220175D02*
X214875Y189147D01*
G01X213575Y189686D02*
Y183996D01*
G01X245364Y221475D02*
X213575Y189686D01*
G01X217778Y209278D02*
X205500Y197000D01*
G01X204961Y198300D02*
X220336Y213675D01*
G01X222800Y44600D02*
X218900Y40700D01*
G01X221500Y45139D02*
X218361Y42000D01*
G01X222800Y46905D02*
Y44600D01*
G01X217900Y51804D02*
X222800Y46905D01*
G01X217900Y65600D02*
Y51804D01*
G01X221500Y46366D02*
Y45139D01*
G01X219672Y48192D02*
X221500Y46366D01*
G01X219672Y48194D02*
Y48192D01*
G01X218532Y49332D02*
X219672Y48194D01*
G01X219800Y67500D02*
X217900Y65600D01*
G01X219800Y102461D02*
Y67500D01*
G01X218500Y103000D02*
Y68039D01*
G01X224400Y107061D02*
X219800Y102461D01*
G01X223100Y107600D02*
X218500Y103000D01*
G01X220650Y114921D02*
Y109311D01*
G01X238744Y133015D02*
X220650Y114921D01*
G01X219350Y115460D02*
Y109850D01*
G01X237444Y133554D02*
X219350Y115460D01*
G01X224400Y113367D02*
Y107061D01*
G01X226135Y115102D02*
X224400Y113367D01*
G01X226771Y115102D02*
X226135D01*
G01X231081Y110793D02*
X226771Y115102D01*
G01X232793Y110793D02*
X231081D01*
G01X234831Y112831D02*
X232793Y110793D01*
G01X230521Y118852D02*
X234831Y114543D01*
G01X230521Y119488D02*
Y118852D01*
G01X231795Y120762D02*
X230521Y119488D01*
G01X232431Y120762D02*
X231795D01*
G01X236741Y116453D02*
X232431Y120762D01*
G01X223100Y113906D02*
Y107600D01*
G01X225596Y116402D02*
X223100Y113906D01*
G01X227310Y116402D02*
X225596D01*
G01X231620Y112093D02*
X227310Y116402D01*
G01X232254Y112093D02*
X231620D01*
G01X233531Y113370D02*
X232254Y112093D01*
G01X229221Y118313D02*
X233531Y114004D01*
G01X229221Y120027D02*
Y118313D01*
G01X231256Y122062D02*
X229221Y120027D01*
G01X220675Y137075D02*
Y126675D01*
G01X219375Y137614D02*
Y127214D01*
G01X232970Y122062D02*
X231256D01*
G01X237280Y117753D02*
X232970Y122062D01*
G01X221427Y149383D02*
Y147658D01*
G01X225052Y153008D02*
X221427Y149383D01*
G01X220127Y149922D02*
Y148197D01*
G01X223752Y153547D02*
X220127Y149922D01*
G01X233300Y149700D02*
X220675Y137075D01*
G01X232000Y150239D02*
X219375Y137614D01*
G01X232000Y162588D02*
Y150239D01*
G01X225052Y170048D02*
Y153008D01*
G01X223752Y170587D02*
Y153547D01*
G01X240721Y171309D02*
X232000Y162588D01*
G01X231525Y176521D02*
X225052Y170048D01*
G01X231525Y182213D02*
Y176521D01*
G01X237112Y187800D02*
X231525Y182213D01*
G01X230225Y177060D02*
X223752Y170587D01*
G01X230225Y182752D02*
Y177060D01*
G01X218625Y187561D02*
Y180171D01*
G01X222375Y186007D02*
Y178617D01*
G01X221075Y186546D02*
Y179156D01*
G01X236573Y189100D02*
X230225Y182752D01*
G01X231689Y200625D02*
X218625Y187561D01*
G01X233243Y196875D02*
X222375Y186007D01*
G01X232704Y198175D02*
X221075Y186546D01*
G01X233378Y200625D02*
X231689D01*
G01X232839Y201925D02*
X231150D01*
G01X235807Y204893D02*
X232839Y201925D01*
G01X234393Y198175D02*
X232704D01*
G01X218966Y209278D02*
X217778D01*
G01X219920Y210232D02*
X218966Y209278D01*
G01X219920Y211420D02*
Y210232D01*
G01X220875Y212375D02*
X219920Y211420D01*
G01X225573Y212375D02*
X220875D01*
G01X228375Y215177D02*
X225573Y212375D01*
G01X225034Y213675D02*
X240334Y228975D01*
G01X220336Y213675D02*
X225034D01*
G01X229563Y215177D02*
X228375D01*
G01X230518Y216132D02*
X229563Y215177D01*
G01X230518Y217320D02*
Y216132D01*
G01X240873Y227675D02*
X230518Y217320D01*
G01X245675Y58564D02*
X255139Y49100D01*
G01X245675Y60757D02*
Y58564D01*
G01X244375Y58025D02*
X254600Y47800D01*
G01X244375Y61296D02*
Y58025D01*
G01X246743Y61825D02*
X245675Y60757D01*
G01X248725Y61825D02*
X246743D01*
G01X246204Y63125D02*
X244375Y61296D01*
G01X248186Y63125D02*
X246204D01*
G01X257700Y72639D02*
X248186Y63125D01*
G01X234831Y114543D02*
Y112831D01*
G01X238453Y116453D02*
X236741D01*
G01X240491Y118491D02*
X238453Y116453D01*
G01X240491Y120203D02*
Y118491D01*
G01X236181Y124512D02*
X240491Y120203D01*
G01X233531Y114004D02*
Y113370D01*
G01X237914Y117753D02*
X237280D01*
G01X239191Y119030D02*
X237914Y117753D01*
G01X239191Y119664D02*
Y119030D01*
G01X234881Y123973D02*
X239191Y119664D01*
G01X238744Y145095D02*
Y133015D01*
G01X237444Y144556D02*
Y133554D01*
G01X236181Y125148D02*
Y124512D01*
G01X237033Y126000D02*
X236181Y125148D01*
G01X238100Y126000D02*
X237033D01*
G01X240100Y124000D02*
X238100Y126000D01*
G01X242947Y124000D02*
X240100D01*
G01X244508Y125561D02*
X242947Y124000D01*
G01X244508Y127392D02*
Y125561D01*
G01X242494Y129406D02*
X244508Y127392D01*
G01X242494Y132594D02*
Y129406D01*
G01X244508Y134608D02*
X242494Y132594D01*
G01X244508Y138186D02*
Y134608D01*
G01X234881Y125687D02*
Y123973D01*
G01X236494Y127300D02*
X234881Y125687D01*
G01X238639Y127300D02*
X236494D01*
G01X240639Y125300D02*
X238639Y127300D01*
G01X242408Y125300D02*
X240639D01*
G01X243208Y126100D02*
X242408Y125300D01*
G01X243208Y126853D02*
Y126100D01*
G01X241195Y128866D02*
X243208Y126853D01*
G01X241193Y128866D02*
X241195D01*
G01X241193Y129405D02*
Y128866D01*
G01X241194Y129406D02*
X241193Y129405D01*
G01X241194Y133133D02*
Y129406D01*
G01X243208Y135147D02*
X241194Y133133D01*
G01X243208Y137647D02*
Y135147D01*
G01X233300Y162049D02*
Y149700D01*
G01X237200Y146639D02*
X238744Y145095D01*
G01X237200Y160645D02*
Y146639D01*
G01X235900Y146100D02*
X237444Y144556D01*
G01X235900Y161184D02*
Y146100D01*
G01X242494Y140200D02*
X244508Y138186D01*
G01X242494Y146650D02*
Y140200D01*
G01X240950Y148194D02*
X242494Y146650D01*
G01X240950Y159091D02*
Y148194D01*
G01X241194Y139661D02*
X243208Y137647D01*
G01X241194Y146111D02*
Y139661D01*
G01X239650Y147655D02*
X241194Y146111D01*
G01X239650Y159630D02*
Y147655D01*
G01X242021Y170770D02*
X233300Y162049D01*
G01X245771Y169216D02*
X237200Y160645D01*
G01X244471Y169755D02*
X235900Y161184D01*
G01X251100Y169241D02*
X240950Y159091D01*
G01X249800Y169780D02*
X239650Y159630D01*
G01X242021Y177128D02*
Y170770D01*
G01X251142Y186249D02*
X242021Y177128D01*
G01X240721Y177667D02*
Y171309D01*
G01X249842Y186788D02*
X240721Y177667D01*
G01X245771Y175574D02*
Y169216D01*
G01X256425Y186228D02*
X245771Y175574D01*
G01X244471Y176113D02*
Y169755D01*
G01X255125Y186767D02*
X244471Y176113D01*
G01X243380Y187800D02*
X237112D01*
G01X257305Y201725D02*
X243380Y187800D01*
G01X242841Y189100D02*
X236573D01*
G01X256766Y203025D02*
X242841Y189100D01*
G01X234932Y196875D02*
X233243D01*
G01X247957Y209900D02*
X234932Y196875D01*
G01X237107Y204354D02*
X233378Y200625D01*
G01X237107Y206075D02*
Y204354D01*
G01X246932Y215900D02*
X237107Y206075D01*
G01X235807Y206614D02*
Y204893D01*
G01X246393Y217200D02*
X235807Y206614D01*
G01X258439Y209900D02*
X247957D01*
G01X247418Y211200D02*
X234393Y198175D01*
G01X257900Y211200D02*
X247418D01*
G01X261483Y215900D02*
X246932D01*
G01X260944Y217200D02*
X246393D01*
G01X244344Y223925D02*
X258600D01*
G01X258061Y225225D02*
X243805D01*
G01X260454Y220175D02*
X245903D01*
G01X259915Y221475D02*
X245364D01*
G01X256947Y227675D02*
X240873D01*
G01X240334Y228975D02*
X256408D01*
G01X263094Y48145D02*
X264282D01*
G01X262139Y49100D02*
X263094Y48145D01*
G01X259780Y49100D02*
X262139D01*
G01X258940Y49940D02*
X259780Y49100D01*
G01X257590Y49940D02*
X258940D01*
G01X256750Y49100D02*
X257590Y49940D01*
G01X255139Y49100D02*
X256750D01*
G01X261600Y47800D02*
X266500Y42900D01*
G01X254600Y47800D02*
X261600D01*
G01X259000Y72100D02*
X248725Y61825D01*
G01X259000Y86839D02*
Y72100D01*
G01X257700Y86300D02*
Y72639D01*
G01X256108Y89731D02*
X259000Y86839D01*
G01X256108Y130969D02*
Y89731D01*
G01X254808Y89192D02*
X257700Y86300D01*
G01X254808Y131508D02*
Y89192D01*
G01X262800Y86439D02*
X264339Y84900D01*
G01X262800Y89461D02*
Y86439D01*
G01X264139Y90800D02*
X262800Y89461D01*
G01X263800Y83600D02*
X267850D01*
G01X261500Y85900D02*
X263800Y83600D01*
G01X261500Y90000D02*
Y85900D01*
G01X263600Y92100D02*
X261500Y90000D01*
G01X260900Y107639D02*
X271150Y97389D01*
G01X266900Y92100D02*
X263600D01*
G01X259600Y107100D02*
X269850Y96850D01*
G01X260900Y126161D02*
Y107639D01*
G01X259600Y126700D02*
Y107100D01*
G01X258200Y133061D02*
X256108Y130969D01*
G01X258200Y159204D02*
Y133061D01*
G01X256900Y133600D02*
X254808Y131508D01*
G01X256900Y159743D02*
Y133600D01*
G01X261950Y127211D02*
X260900Y126161D01*
G01X261950Y144620D02*
Y127211D01*
G01X260650Y127750D02*
X259600Y126700D01*
G01X260650Y158189D02*
Y127750D01*
G01X262790Y145460D02*
X261950Y144620D01*
G01X262790Y146810D02*
Y145460D01*
G01X261950Y147650D02*
X262790Y146810D01*
G01X261950Y149000D02*
Y147650D01*
G01X262790Y149840D02*
X261950Y149000D01*
G01X262790Y151190D02*
Y149840D01*
G01X261950Y152030D02*
X262790Y151190D01*
G01X268046Y169050D02*
X258200Y159204D01*
G01X267507Y170350D02*
X256900Y159743D01*
G01X261950Y153380D02*
Y152030D01*
G01X262790Y154220D02*
X261950Y153380D01*
G01X262790Y155570D02*
Y154220D01*
G01X261950Y156410D02*
X262790Y155570D01*
G01X261950Y157650D02*
Y156410D01*
G01X269600Y165300D02*
X261950Y157650D01*
G01X269061Y166600D02*
X260650Y158189D01*
G01X251100Y175595D02*
Y169241D01*
G01X253805Y178300D02*
X251100Y175595D01*
G01X257216Y178300D02*
X253805D01*
G01X270266Y191350D02*
X257216Y178300D01*
G01X249800Y176134D02*
Y169780D01*
G01X253266Y179600D02*
X249800Y176134D01*
G01X256677Y179600D02*
X253266D01*
G01X269727Y192650D02*
X256677Y179600D01*
G01X251142Y190258D02*
Y186249D01*
G01X258859Y197975D02*
X251142Y190258D01*
G01X249842Y190797D02*
Y186788D01*
G01X258320Y199275D02*
X249842Y190797D01*
G01X256425Y190237D02*
Y186228D01*
G01X260413Y194225D02*
X256425Y190237D01*
G01X267837Y194225D02*
X260413D01*
G01X255125Y190776D02*
Y186767D01*
G01X259874Y195525D02*
X255125Y190776D01*
G01X267298Y195525D02*
X259874D01*
G01X264729Y201725D02*
X257305D01*
G01X264190Y203025D02*
X256766D01*
G01X266283Y197975D02*
X258859D01*
G01X265744Y199275D02*
X258320D01*
G01X260689Y212150D02*
X258439Y209900D01*
G01X265571Y212150D02*
X260689D01*
G01X260150Y213450D02*
X257900Y211200D01*
G01X276383Y230800D02*
X261483Y215900D01*
G01X275844Y232100D02*
X260944Y217200D01*
G01X265032Y213450D02*
X260150D01*
G01X258600Y223925D02*
X274925Y240250D01*
G01X274386Y241550D02*
X258061Y225225D01*
G01X274929Y234650D02*
X260454Y220175D01*
G01X274390Y235950D02*
X259915Y221475D01*
G01X273422Y244150D02*
X256947Y227675D01*
G01X256408Y228975D02*
X272883Y245450D01*
G01X267800Y41600D02*
X268910Y40490D01*
G01X267800Y43439D02*
Y41600D01*
G01X265236Y46003D02*
X267800Y43439D01*
G01X266500Y41850D02*
X265140Y40490D01*
G01X266500Y42900D02*
Y41850D01*
G01X265236Y47191D02*
Y46003D01*
G01X264282Y48145D02*
X265236Y47191D01*
G01X278514Y68100D02*
X282075Y64539D01*
G01X273939Y68100D02*
X278514D01*
G01X271150Y70889D02*
X273939Y68100D01*
G01X271150Y82139D02*
Y70889D01*
G01X277975Y66800D02*
X280775Y64000D01*
G01X273400Y66800D02*
X277975D01*
G01X269850Y70350D02*
X273400Y66800D01*
G01X269850Y81600D02*
Y70350D01*
G01X268389Y84900D02*
X271150Y82139D01*
G01X264339Y84900D02*
X268389D01*
G01X267850Y83600D02*
X269850Y81600D01*
G01X278269Y80870D02*
X281130D01*
G01X277300Y81839D02*
X278269Y80870D01*
G01X277300Y83661D02*
Y81839D01*
G01X278039Y84400D02*
X277300Y83661D01*
G01X280464Y84400D02*
X278039D01*
G01X277730Y79570D02*
X280591D01*
G01X277350Y79950D02*
X277730Y79570D01*
G01X277349Y79950D02*
X277350D01*
G01X276000Y81300D02*
X277349Y79950D01*
G01X276000Y84200D02*
Y81300D01*
G01X277500Y85700D02*
X276000Y84200D01*
G01X279925Y85700D02*
X277500D01*
G01X267439Y90800D02*
X264139D01*
G01X271150Y94511D02*
X267439Y90800D01*
G01X271150Y97389D02*
Y94511D01*
G01X269850Y95050D02*
X266900Y92100D01*
G01X269850Y96850D02*
Y95050D01*
G01X277539Y93800D02*
X280339D01*
G01X276075Y95264D02*
X277539Y93800D01*
G01X276075Y102636D02*
Y95264D01*
G01X277339Y103900D02*
X276075Y102636D01*
G01X279839Y103900D02*
X277339D01*
G01X277000Y92500D02*
X279800D01*
G01X274775Y94725D02*
X277000Y92500D01*
G01X274775Y103175D02*
Y94725D01*
G01X276800Y105200D02*
X274775Y103175D01*
G01X279300Y105200D02*
X276800D01*
G01X280385Y106285D02*
X279300Y105200D01*
G01X278300Y111500D02*
X280200D01*
G01X276075Y113725D02*
X278300Y111500D01*
G01X276075Y130757D02*
Y113725D01*
G01X277761Y110200D02*
X279661D01*
G01X274775Y113186D02*
X277761Y110200D01*
G01X274775Y115665D02*
Y113186D01*
G01X273935Y116505D02*
X274775Y115665D01*
G01X273935Y117855D02*
Y116505D01*
G01X274775Y118695D02*
X273935Y117855D01*
G01X274775Y120045D02*
Y118695D01*
G01X273935Y120885D02*
X274775Y120045D01*
G01X287800Y142482D02*
X276075Y130757D01*
G01X273935Y122235D02*
Y120885D01*
G01X274775Y123075D02*
X273935Y122235D01*
G01X274775Y131296D02*
Y123075D01*
G01X276662Y133183D02*
X274775Y131296D01*
G01X276662Y134371D02*
Y133183D01*
G01X277616Y135325D02*
X276662Y134371D01*
G01X278804Y135325D02*
X277616D01*
G01X279759Y136280D02*
X278804Y135325D01*
G01X284731Y165300D02*
X269600D01*
G01X284192Y166600D02*
X269061D01*
G01X279600Y169050D02*
X268046D01*
G01X279061Y170350D02*
X267507D01*
G01X289150Y180439D02*
X279061Y170350D01*
G01X267158Y198850D02*
X266283Y197975D01*
G01X268712Y195100D02*
X267837Y194225D01*
G01X278008Y195100D02*
X268712D01*
G01X286908Y204000D02*
X278008Y195100D01*
G01X268173Y196400D02*
X267298Y195525D01*
G01X277469Y196400D02*
X268173D01*
G01X286369Y205300D02*
X277469Y196400D01*
G01X279562Y191350D02*
X270266D01*
G01X279023Y192650D02*
X269727D01*
G01X287491Y201118D02*
X279023Y192650D01*
G01X265604Y202600D02*
X264729Y201725D01*
G01X274900Y202600D02*
X265604D01*
G01X292400Y220100D02*
X274900Y202600D01*
G01X265065Y203900D02*
X264190Y203025D01*
G01X274361Y203900D02*
X265065D01*
G01X291861Y221400D02*
X274361Y203900D01*
G01X276454Y198850D02*
X267158D01*
G01X286054Y208450D02*
X276454Y198850D01*
G01X266619Y200150D02*
X265744Y199275D01*
G01X275915Y200150D02*
X266619D01*
G01X285515Y209750D02*
X275915Y200150D01*
G01X272321Y218900D02*
X265571Y212150D01*
G01X275968Y218900D02*
X272321D01*
G01X284118Y227050D02*
X275968Y218900D01*
G01X271782Y220200D02*
X265032Y213450D01*
G01X275429Y220200D02*
X271782D01*
G01X283579Y228350D02*
X275429Y220200D01*
G01X322600Y230800D02*
X276383D01*
G01X323139Y232100D02*
X275844D01*
G01X274925Y240250D02*
X327250D01*
G01X327789Y241550D02*
X274386D01*
G01X322911Y234650D02*
X274929D01*
G01X323450Y235950D02*
X274390D01*
G01X272883Y245450D02*
X353339D01*
G01X352800Y244150D02*
X273422D01*
G01X283523Y41725D02*
X284758Y40490D01*
G01X283523Y53602D02*
Y41725D01*
G01X282223D02*
X280988Y40490D01*
G01X282223Y53063D02*
Y41725D01*
G01X282075Y55050D02*
X283523Y53602D01*
G01X282075Y64539D02*
Y55050D01*
G01X280775Y54511D02*
X282223Y53063D01*
G01X280775Y64000D02*
Y54511D01*
G01X293919Y49120D02*
X299271Y43768D01*
G01X293919Y54080D02*
Y49120D01*
G01X295650Y55811D02*
X293919Y54080D01*
G01X292619Y48581D02*
X297971Y43229D01*
G01X292619Y54619D02*
Y48581D01*
G01X294350Y56350D02*
X292619Y54619D01*
G01X294350Y62211D02*
Y56350D01*
G01X294200Y64200D02*
X295650Y62750D01*
G01X288739Y64200D02*
X294200D01*
G01X285905Y67034D02*
X288739Y64200D01*
G01X285905Y70339D02*
Y67034D01*
G01X283600Y72644D02*
X285905Y70339D01*
G01X283600Y78400D02*
Y72644D01*
G01X293661Y62900D02*
X294350Y62211D01*
G01X288200Y62900D02*
X293661D01*
G01X284605Y66495D02*
X288200Y62900D01*
G01X284605Y69800D02*
Y66495D01*
G01X282300Y72105D02*
X284605Y69800D01*
G01X282300Y77861D02*
Y72105D01*
G01X290639Y74300D02*
X293439Y77100D01*
G01X288500Y74300D02*
X290639D01*
G01X286550Y76250D02*
X288500Y74300D01*
G01X281130Y80870D02*
X283600Y78400D01*
G01X283225Y87161D02*
X280464Y84400D01*
G01X283225Y90914D02*
Y87161D01*
G01X280591Y79570D02*
X282300Y77861D01*
G01X281925Y87700D02*
X279925Y85700D01*
G01X281925Y90375D02*
Y87700D01*
G01X292900Y78400D02*
X294834D01*
G01X290100Y75600D02*
X292900Y78400D01*
G01X289039Y75600D02*
X290100D01*
G01X287850Y76789D02*
X289039Y75600D01*
G01X287850Y78600D02*
Y76789D01*
G01X289847Y80597D02*
X287850Y78600D01*
G01X289847Y83292D02*
Y80597D01*
G01X287850Y85289D02*
X289847Y83292D01*
G01X287850Y91689D02*
Y85289D01*
G01X294295Y77100D02*
X299295Y72100D01*
G01X293439Y77100D02*
X294295D01*
G01X286550Y79139D02*
Y76250D01*
G01X288547Y81136D02*
X286550Y79139D01*
G01X288547Y82753D02*
Y81136D01*
G01X286550Y84750D02*
X288547Y82753D01*
G01X286550Y91150D02*
Y84750D01*
G01X291800Y86739D02*
X300989Y77550D01*
G01X291800Y105600D02*
Y86739D01*
G01X290500Y86200D02*
X300450Y76250D01*
G01X290500Y106139D02*
Y86200D01*
G01X280339Y93800D02*
X283225Y90914D01*
G01X281685Y105746D02*
X279839Y103900D01*
G01X279800Y92500D02*
X281925Y90375D01*
G01X286275Y93264D02*
X287850Y91689D01*
G01X286275Y114636D02*
Y93264D01*
G01X284975Y92725D02*
X286550Y91150D01*
G01X284975Y100854D02*
Y92725D01*
G01X284135Y101694D02*
X284975Y100854D01*
G01X284135Y103044D02*
Y101694D01*
G01X284975Y103884D02*
X284135Y103044D01*
G01X284975Y105234D02*
Y103884D01*
G01X284135Y106074D02*
X284975Y105234D01*
G01X281685Y110015D02*
Y105746D01*
G01X280200Y111500D02*
X281685Y110015D01*
G01X280385Y109476D02*
Y106285D01*
G01X279661Y110200D02*
X280385Y109476D01*
G01X289950Y118311D02*
X286275Y114636D01*
G01X289950Y121239D02*
Y118311D01*
G01X284135Y107424D02*
Y106074D01*
G01X284975Y108264D02*
X284135Y107424D01*
G01X284975Y115175D02*
Y108264D01*
G01X288650Y118850D02*
X284975Y115175D01*
G01X288650Y120700D02*
Y118850D01*
G01X287350Y122000D02*
X288650Y120700D01*
G01X293700Y107500D02*
X291800Y105600D01*
G01X293700Y136200D02*
Y107500D01*
G01X292400Y108039D02*
X290500Y106139D01*
G01X292400Y136739D02*
Y108039D01*
G01X287889Y123300D02*
X289950Y121239D01*
G01X283439Y123300D02*
X287889D01*
G01X282600Y124139D02*
X283439Y123300D01*
G01X282600Y125061D02*
Y124139D01*
G01X283339Y125800D02*
X282600Y125061D01*
G01X287039Y125800D02*
X283339D01*
G01X289950Y128711D02*
X287039Y125800D01*
G01X289950Y137754D02*
Y128711D01*
G01X282900Y122000D02*
X287350D01*
G01X281300Y123600D02*
X282900Y122000D01*
G01X281300Y125600D02*
Y123600D01*
G01X282800Y127100D02*
X281300Y125600D01*
G01X286500Y127100D02*
X282800D01*
G01X288650Y129250D02*
X286500Y127100D01*
G01X288650Y138293D02*
Y129250D01*
G01X295300Y137800D02*
X293700Y136200D01*
G01X287800Y163065D02*
Y142482D01*
G01X279759Y137468D02*
Y136280D01*
G01X280713Y138422D02*
X279759Y137468D01*
G01X281901Y138422D02*
X280713D01*
G01X286500Y143021D02*
X281901Y138422D01*
G01X286500Y163604D02*
Y143021D01*
G01X291550Y139354D02*
X289950Y137754D01*
G01X291550Y161511D02*
Y139354D01*
G01X290250Y139893D02*
X288650Y138293D01*
G01X290250Y162050D02*
Y139893D01*
G01X294000Y138339D02*
X292400Y136739D01*
G01X294000Y148069D02*
Y138339D01*
G01X299040Y153109D02*
X294000Y148069D01*
G01X294250Y174819D02*
X284731Y165300D01*
G01X292950Y175358D02*
X284192Y166600D01*
G01X297050Y172315D02*
X287800Y163065D01*
G01X295750Y172854D02*
X286500Y163604D01*
G01X300050Y170011D02*
X291550Y161511D01*
G01X298750Y170550D02*
X290250Y162050D01*
G01X290450Y179900D02*
X279600Y169050D01*
G01X290450Y190553D02*
Y179900D01*
G01X289150Y191092D02*
Y180439D01*
G01X294250Y189049D02*
Y174819D01*
G01X292950Y189588D02*
Y175358D01*
G01X288030Y199818D02*
X279562Y191350D01*
G01X295397Y195500D02*
X290450Y190553D01*
G01X294858Y196800D02*
X289150Y191092D01*
G01X297751Y192550D02*
X294250Y189049D01*
G01X297212Y193850D02*
X292950Y189588D01*
G01X306736Y208450D02*
X286054D01*
G01X306197Y209750D02*
X285515D01*
G01X303000Y204000D02*
X286908D01*
G01X302461Y205300D02*
X286369D01*
G01X316100Y199818D02*
X288030D01*
G01X316100Y201118D02*
X287491D01*
G01X320300Y220100D02*
X292400D01*
G01X320300Y221400D02*
X291861D01*
G01X322296Y227050D02*
X284118D01*
G01X322836Y228350D02*
X283579D01*
G01X299271Y41725D02*
X300506Y40490D01*
G01X299271Y43768D02*
Y41725D01*
G01X297971D02*
X296736Y40490D01*
G01X297971Y43229D02*
Y41725D01*
G01X308061Y43300D02*
X313200D01*
G01X298700Y52661D02*
X308061Y43300D01*
G01X295650Y62750D02*
Y55811D01*
G01X308600Y44600D02*
X313739D01*
G01X300000Y53200D02*
X308600Y44600D01*
G01X300000Y61600D02*
Y53200D01*
G01X298700Y62139D02*
Y52661D01*
G01X302100Y63700D02*
X300000Y61600D01*
G01X305100Y63700D02*
X302100D01*
G01X307901Y60900D02*
X305100Y63700D01*
G01X311280Y60900D02*
X307901D01*
G01X306879Y73020D02*
X313380Y66517D01*
G01X306880Y73020D02*
X306879D01*
G01X306500Y73400D02*
X306880Y73020D01*
G01X299834Y73400D02*
X306500D01*
G01X294834Y78400D02*
X299834Y73400D01*
G01X301561Y65000D02*
X298700Y62139D01*
G01X305639Y65000D02*
X301561D01*
G01X308440Y62200D02*
X305639Y65000D01*
G01X310741Y62200D02*
X308440D01*
G01X305960Y72100D02*
X312080Y65978D01*
G01X299295Y72100D02*
X305960D01*
G01X307250Y76250D02*
X325000Y58500D01*
G01X307789Y77550D02*
X326300Y59039D01*
G01X300989Y77550D02*
X307789D01*
G01X300450Y76250D02*
X307250D01*
G01X295300Y147530D02*
Y137800D01*
G01X300340Y152570D02*
X295300Y147530D01*
G01X300340Y162140D02*
Y152570D01*
G01X305700Y167500D02*
X300340Y162140D01*
G01X299040Y162679D02*
Y153109D01*
G01X305161Y168800D02*
X299040Y162679D01*
G01X297050Y183990D02*
Y172315D01*
G01X295750Y184529D02*
Y172854D01*
G01X300050Y182400D02*
Y170011D01*
G01X301352Y183702D02*
X300050Y182400D01*
G01X298750Y182939D02*
Y170550D01*
G01X311900Y167500D02*
X305700D01*
G01X311361Y168800D02*
X305161D01*
G01X299900Y195500D02*
X295397D01*
G01X301670Y197270D02*
X299900Y195500D01*
G01X311420Y197270D02*
X301670D01*
G01X299361Y196800D02*
X294858D01*
G01X301131Y198570D02*
X299361Y196800D01*
G01X316220Y192550D02*
X297751D01*
G01X315681Y193850D02*
X297212D01*
G01X300160Y187100D02*
X297050Y183990D01*
G01X301840Y187100D02*
X300160D01*
G01X303480Y188740D02*
X301840Y187100D01*
G01X303480Y189100D02*
Y188740D01*
G01X299621Y188400D02*
X295750Y184529D01*
G01X301000Y188400D02*
X299621D01*
G01X301300Y188700D02*
X301000Y188400D01*
G01X307102Y183702D02*
X301352D01*
G01X309100Y185700D02*
X307102Y183702D01*
G01X309100Y187397D02*
Y185700D01*
G01X309700Y187997D02*
X309100Y187397D01*
G01X300813Y185002D02*
X298750Y182939D01*
G01X306563Y185002D02*
X300813D01*
G01X307800Y186239D02*
X306563Y185002D01*
G01X307800Y187700D02*
Y186239D01*
G01X307500Y188000D02*
X307800Y187700D01*
G01X311609Y213323D02*
X306736Y208450D01*
G01X313786Y217339D02*
X306197Y209750D01*
G01X304050Y205050D02*
X303000Y204000D01*
G01X305500Y205050D02*
X304050D01*
G01X303511Y206350D02*
X302461Y205300D01*
G01X305500Y206350D02*
X303511D01*
G01X315800Y198570D02*
X301131D01*
G01X315000Y41944D02*
X316254Y40690D01*
G01X315000Y43339D02*
Y41944D01*
G01X313739Y44600D02*
X315000Y43339D01*
G01X313700Y41906D02*
X312484Y40690D01*
G01X313700Y42800D02*
Y41906D01*
G01X313200Y43300D02*
X313700Y42800D01*
G01X325000Y55900D02*
X324000Y54900D01*
G01X325000Y58500D02*
Y55900D01*
G01X313380Y63000D02*
X311280Y60900D01*
G01X313380Y66517D02*
Y63000D01*
G01X312080Y63539D02*
X310741Y62200D01*
G01X312080Y65978D02*
Y63539D01*
G01X315256Y170856D02*
X311900Y167500D01*
G01X316444Y170856D02*
X315256D01*
G01X317398Y171810D02*
X316444Y170856D01*
G01X317398Y172998D02*
Y171810D01*
G01X318353Y173953D02*
X317398Y172998D01*
G01X319541Y173953D02*
X318353D01*
G01X320495Y174907D02*
X319541Y173953D01*
G01X320495Y176095D02*
Y174907D01*
G01X321450Y177050D02*
X320495Y176095D01*
G01X322300Y177050D02*
X321450D01*
G01X320911Y178350D02*
X311361Y168800D01*
G01X322300Y178350D02*
X320911D01*
G01X312260Y196430D02*
X311420Y197270D01*
G01X313610Y196430D02*
X312260D01*
G01X314450Y197270D02*
X313610Y196430D01*
G01X315800Y197270D02*
X314450D01*
G01X318560Y194890D02*
X316220Y192550D01*
G01X319801Y194890D02*
X318560D01*
G01X316844Y195013D02*
X315681Y193850D01*
G01X316844Y196010D02*
Y195013D01*
G01X312797Y213323D02*
X311609D01*
G01X313751Y214277D02*
X312797Y213323D01*
G01X313751Y215465D02*
Y214277D01*
G01X314706Y216420D02*
X313751Y215465D01*
G01X330449Y222951D02*
X322600Y230800D01*
G01X326287Y223059D02*
X322296Y227050D01*
G01X327207Y223979D02*
X322836Y228350D01*
G01X331368Y223871D02*
X323139Y232100D01*
G01X333093Y224468D02*
X322911Y234650D01*
G01X334013Y225387D02*
X323450Y235950D01*
G01X326300Y56000D02*
X327400Y54900D01*
G01X326300Y59039D02*
Y56000D01*
G01X336000Y228046D02*
X338486Y225560D01*
G01X336000Y231500D02*
Y228046D01*
G01X337300Y228585D02*
Y232039D01*
G01X339405Y226480D02*
X337300Y228585D01*
G01X327250Y240250D02*
X336000Y231500D01*
G01X337300Y232039D02*
X327789Y241550D01*
G01X353339Y245450D02*
X368489Y230300D01*
G01X367950Y229000D02*
X352800Y244150D01*
G01X368489Y230300D02*
X372461D01*
G01X373000Y229000D02*
X367950D01*
G01X379651Y243000D02*
X390839D01*
G01X376200Y239549D02*
X379651Y243000D01*
G01X376200Y234039D02*
Y239549D01*
G01X372461Y230300D02*
X376200Y234039D01*
G01X377500Y233500D02*
X373000Y229000D01*
G01X377500Y239010D02*
Y233500D01*
G01X380190Y241700D02*
X377500Y239010D01*
G01X381540Y241700D02*
X380190D01*
G01X382380Y240860D02*
X381540Y241700D01*
G01X383730Y240860D02*
X382380D01*
G01X384570Y241700D02*
X383730Y240860D01*
G01X385920Y241700D02*
X384570D01*
G01X386760Y240860D02*
X385920Y241700D01*
G01X388110Y240860D02*
X386760D01*
G01X392711Y241128D02*
X394229D01*
G01X390839Y243000D02*
X392711Y241128D01*
G01X388950Y241700D02*
X388110Y240860D01*
G01X390300Y241700D02*
X388950D01*
G01X391788Y240212D02*
X390300Y241700D01*
G01X391788Y238760D02*
Y240212D01*
G54D14*
G01X432509Y90209D02*
X448218Y74500D01*
G01X450266Y78900D02*
X432628Y96538D01*
G01X433676Y91376D02*
X448902Y76150D01*
G01X448218Y74500D02*
X485126D01*
G01X450950Y80550D02*
X433700Y97800D01*
G01X449140Y86250D02*
X436575Y98815D01*
G01X449824Y87900D02*
X438225Y99499D01*
G01X448902Y76150D02*
X562050D01*
G01X436575Y98815D02*
Y100100D01*
G01X438225Y99499D02*
Y100100D01*
G01X448820Y93074D02*
X440575Y101319D01*
G01X451534Y93074D02*
X448820D01*
G01X449504Y94724D02*
X441742Y102486D01*
G01X568926Y78900D02*
X450266D01*
G01X588450Y80550D02*
X450950D01*
G01X460950Y86250D02*
X449140D01*
G01X463350Y83850D02*
X460950Y86250D01*
G01X475241Y83850D02*
X463350D01*
G01X461634Y87900D02*
X449824D01*
G01X464034Y85500D02*
X461634Y87900D01*
G01X474557Y85500D02*
X464034D01*
G01X452424Y92184D02*
X451534Y93074D01*
G01X454674Y92184D02*
X452424D01*
G01X455564Y93074D02*
X454674Y92184D01*
G01X457814Y93074D02*
X455564D01*
G01X458704Y92184D02*
X457814Y93074D01*
G01X460954Y92184D02*
X458704D01*
G01X461844Y93074D02*
X460954Y92184D01*
G01X464624Y93074D02*
X461844D01*
G01X458414Y94724D02*
X449504D01*
G01X459257Y93881D02*
X458414Y94724D01*
G01X460317Y93881D02*
X459257D01*
G01X461160Y94724D02*
X460317Y93881D01*
G01X465308Y94724D02*
X461160D01*
G01X476957Y85566D02*
X475241Y83850D01*
G01X476957Y87150D02*
Y85566D01*
G01X477707Y87900D02*
X476957Y87150D01*
G01X479207Y87900D02*
X477707D01*
G01X479957Y87150D02*
X479207Y87900D01*
G01X475307Y86250D02*
X474557Y85500D01*
G01X475307Y87834D02*
Y86250D01*
G01X477023Y89550D02*
X475307Y87834D01*
G01X479891Y89550D02*
X477023D01*
G01X481607Y87834D02*
X479891Y89550D01*
G01X466340Y91358D02*
X464624Y93074D01*
G01X470708Y91358D02*
X466340D01*
G01X472424Y93074D02*
X470708Y91358D01*
G01X505784Y93074D02*
X472424D01*
G01X467024Y93008D02*
X465308Y94724D01*
G01X470024Y93008D02*
X467024D01*
G01X471740Y94724D02*
X470024Y93008D01*
G01X599176Y94724D02*
X471740D01*
G01X494945Y74500D02*
X495835Y73610D01*
G01X489156Y74500D02*
X494945D01*
G01X488266Y73610D02*
X489156Y74500D01*
G01X486016Y73610D02*
X488266D01*
G01X485126Y74500D02*
X486016Y73610D01*
G01X479957Y85566D02*
Y87150D01*
G01X481673Y83850D02*
X479957Y85566D01*
G01X484541Y83850D02*
X481673D01*
G01X486257Y85566D02*
X484541Y83850D01*
G01X486257Y87600D02*
Y85566D01*
G01X486857Y88200D02*
X486257Y87600D01*
G01X488657Y88200D02*
X486857D01*
G01X489257Y87600D02*
X488657Y88200D01*
G01X489257Y85566D02*
Y87600D01*
G01X490973Y83850D02*
X489257Y85566D01*
G01X601250Y83850D02*
X490973D01*
G01X481607Y86250D02*
Y87834D01*
G01X482357Y85500D02*
X481607Y86250D01*
G01X483857Y85500D02*
X482357D01*
G01X484607Y86250D02*
X483857Y85500D01*
G01X484607Y88284D02*
Y86250D01*
G01X486173Y89850D02*
X484607Y88284D01*
G01X489341Y89850D02*
X486173D01*
G01X490907Y88284D02*
X489341Y89850D01*
G01X490907Y86250D02*
Y88284D01*
G01X491657Y85500D02*
X490907Y86250D01*
G01X601934Y85500D02*
X491657D01*
G01X510645Y73610D02*
X511535Y74500D01*
G01X508395Y73610D02*
X510645D01*
G01X507505Y74500D02*
X508395Y73610D01*
G01X505255Y74500D02*
X507505D01*
G01X504365Y73610D02*
X505255Y74500D01*
G01X502115Y73610D02*
X504365D01*
G01X501225Y74500D02*
X502115Y73610D01*
G01X498975Y74500D02*
X501225D01*
G01X498085Y73610D02*
X498975Y74500D01*
G01X495835Y73610D02*
X498085D01*
G01X506674Y92184D02*
X505784Y93074D01*
G01X508924Y92184D02*
X506674D01*
G01X509814Y93074D02*
X508924Y92184D01*
G01X582286Y93074D02*
X509814D01*
G01X525805Y74500D02*
X528055D01*
G01X524915Y73610D02*
X525805Y74500D01*
G01X522665Y73610D02*
X524915D01*
G01X521775Y74500D02*
X522665Y73610D01*
G01X519525Y74500D02*
X521775D01*
G01X518635Y73610D02*
X519525Y74500D01*
G01X516385Y73610D02*
X518635D01*
G01X515495Y74500D02*
X516385Y73610D01*
G01X511535Y74500D02*
X515495D01*
G01X532085D02*
X542526D01*
G01X531195Y73610D02*
X532085Y74500D01*
G01X528945Y73610D02*
X531195D01*
G01X528055Y74500D02*
X528945Y73610D01*
G01X555976D02*
X558226D01*
G01X555086Y74500D02*
X555976Y73610D01*
G01X552836Y74500D02*
X555086D01*
G01X551946Y73610D02*
X552836Y74500D01*
G01X549696Y73610D02*
X551946D01*
G01X548806Y74500D02*
X549696Y73610D01*
G01X546556Y74500D02*
X548806D01*
G01X545666Y73610D02*
X546556Y74500D01*
G01X543416Y73610D02*
X545666D01*
G01X542526Y74500D02*
X543416Y73610D01*
G01X570734Y59375D02*
X572450Y61091D01*
G01X566616Y59375D02*
X570734D01*
G01X565050Y60941D02*
X566616Y59375D01*
G01X565050Y70816D02*
Y60941D01*
G01X561366Y74500D02*
X565050Y70816D01*
G01X559116Y74500D02*
X561366D01*
G01X558226Y73610D02*
X559116Y74500D01*
G01X570800Y71784D02*
X572366Y73350D01*
G01X570800Y61775D02*
Y71784D01*
G01X570050Y61025D02*
X570800Y61775D01*
G01X567300Y61025D02*
X570050D01*
G01X566700Y61625D02*
X567300Y61025D01*
G01X566700Y71500D02*
Y61625D01*
G01X562050Y76150D02*
X566700Y71500D01*
G01X569816Y78010D02*
X568926Y78900D01*
G01X572066Y78010D02*
X569816D01*
G01X572956Y78900D02*
X572066Y78010D01*
G01X586466Y59375D02*
X613367D01*
G01X584750Y61091D02*
X586466Y59375D01*
G01X580034D02*
X581750Y61091D01*
G01X577166Y59375D02*
X580034D01*
G01X575450Y61091D02*
X577166Y59375D01*
G01X584750Y70900D02*
Y61091D01*
G01X584150Y71500D02*
X584750Y70900D01*
G01X582350Y71500D02*
X584150D01*
G01X581750Y70900D02*
X582350Y71500D01*
G01X581750Y61091D02*
Y70900D01*
G01X575450Y71100D02*
Y61091D01*
G01X574850Y71700D02*
X575450Y71100D01*
G01X573050Y71700D02*
X574850D01*
G01X572450Y71100D02*
X573050Y71700D01*
G01X572450Y61091D02*
Y71100D01*
G01X587150Y61025D02*
X614051D01*
G01X586400Y61775D02*
X587150Y61025D01*
G01X586400Y71584D02*
Y61775D01*
G01X584834Y73150D02*
X586400Y71584D01*
G01X581666Y73150D02*
X584834D01*
G01X580100Y71584D02*
X581666Y73150D01*
G01X580100Y61775D02*
Y71584D01*
G01X579350Y61025D02*
X580100Y61775D01*
G01X577850Y61025D02*
X579350D01*
G01X577100Y61775D02*
X577850Y61025D01*
G01X577100Y71784D02*
Y61775D01*
G01X575534Y73350D02*
X577100Y71784D01*
G01X572366Y73350D02*
X575534D01*
G01X587766Y78900D02*
X572956D01*
G01X589350Y77316D02*
X587766Y78900D01*
G01X583176Y92184D02*
X582286Y93074D01*
G01X585426Y92184D02*
X583176D01*
G01X586316Y93074D02*
X585426Y92184D01*
G01X598492Y93074D02*
X586316D01*
G01X589350Y65516D02*
Y77316D01*
G01X590916Y63950D02*
X589350Y65516D01*
G01X595034Y63950D02*
X590916D01*
G01X596750Y65666D02*
X595034Y63950D01*
G01X596750Y74900D02*
Y65666D01*
G01X597350Y75500D02*
X596750Y74900D01*
G01X599750D02*
X599150Y75500D01*
G01X599750Y65666D02*
Y74900D01*
G01X601466Y63950D02*
X599750Y65666D01*
G01X615016Y63950D02*
X601466D01*
G01X591000Y66200D02*
Y78000D01*
G01X591600Y65600D02*
X591000Y66200D01*
G01X594350Y65600D02*
X591600D01*
G01X595100Y66350D02*
X594350Y65600D01*
G01X595100Y75584D02*
Y66350D01*
G01X601400D02*
Y75584D01*
G01X602150Y65600D02*
X601400Y66350D01*
G01X615700Y65600D02*
X602150D01*
G01X599150Y75500D02*
X597350D01*
G01X591000Y78000D02*
X588450Y80550D01*
G01X596666Y77150D02*
X595100Y75584D01*
G01X599834Y77150D02*
X596666D01*
G01X601400Y75584D02*
X599834Y77150D01*
G01X605400Y79700D02*
X601250Y83850D01*
G01X607050Y80384D02*
X601934Y85500D01*
G01X609800Y81766D02*
X598492Y93074D01*
G01X611450Y82450D02*
X599176Y94724D01*
G01X613367Y59375D02*
X628690Y44052D01*
G01X614051Y61025D02*
X634676Y40400D01*
G01X628016Y50950D02*
X615016Y63950D01*
G01X628700Y52600D02*
X615700Y65600D01*
G01X605400Y71200D02*
Y79700D01*
G01X607500Y69100D02*
X605400Y71200D01*
G01X616242Y69100D02*
X607500D01*
G01X627492Y57850D02*
X616242Y69100D01*
G01X607050Y71884D02*
Y80384D01*
G01X608184Y70750D02*
X607050Y71884D01*
G01X616926Y70750D02*
X608184D01*
G01X628176Y59500D02*
X616926Y70750D01*
G01X613316Y73700D02*
X609800Y77216D01*
G01X617866Y73700D02*
X613316D01*
G01X629116Y62450D02*
X617866Y73700D01*
G01X609800Y77216D02*
Y81766D01*
G01X611450Y77900D02*
Y82450D01*
G01X614000Y75350D02*
X611450Y77900D01*
G01X618550Y75350D02*
X614000D01*
G01X629800Y64100D02*
X618550Y75350D01*
G01X631540Y41202D02*
X633992Y38750D01*
G01X630281Y41202D02*
X631540D01*
G01X628690Y42793D02*
X630281Y41202D01*
G01X628690Y44052D02*
Y42793D01*
G01X634516Y50950D02*
X628016D01*
G01X635200Y52600D02*
X628700D01*
G01X641716Y57850D02*
X627492D01*
G01X642400Y59500D02*
X628176D01*
G01X643516Y62450D02*
X629116D01*
G01X644200Y64100D02*
X629800D01*
G01X644193Y12907D02*
X643200Y13900D01*
G01X648962Y12707D02*
X650200Y13945D01*
G01X648800Y12707D02*
X648962D01*
G01X644250Y22791D02*
X652000Y30541D01*
G01X644250Y20007D02*
Y22791D01*
G01X643200Y18957D02*
X644250Y20007D01*
G01X643200Y13900D02*
Y18957D01*
G01X645900Y22107D02*
X653325Y29532D01*
G01X645900Y19323D02*
Y22107D01*
G01X644850Y18273D02*
X645900Y19323D01*
G01X644850Y15957D02*
Y18273D01*
G01X645300Y15507D02*
X644850Y15957D01*
G01X648550Y22991D02*
X654800Y29241D01*
G01X648550Y15640D02*
Y22991D01*
G01X648400Y15490D02*
X648550Y15640D01*
G01X637491Y41982D02*
X635350Y44123D01*
G01X644346Y41982D02*
X637491D01*
G01X646625Y39703D02*
X644346Y41982D01*
G01X646625Y29982D02*
Y39703D01*
G01X647000Y29607D02*
X646625Y29982D01*
G01X638175Y43632D02*
X637000Y44807D01*
G01X645030Y43632D02*
X638175D01*
G01X648275Y40387D02*
X645030Y43632D01*
G01X648275Y32082D02*
Y40387D01*
G01X649550Y30807D02*
X648275Y32082D01*
G01X643700Y33390D02*
Y33290D01*
G01X643825Y33515D02*
X643700Y33390D01*
G01X643825Y35748D02*
Y33515D01*
G01X640823Y38750D02*
X643825Y35748D01*
G01X633992Y38750D02*
X640823D01*
G01X645475Y31682D02*
X644100Y30307D01*
G01X645475Y36432D02*
Y31682D01*
G01X641507Y40400D02*
X645475Y36432D01*
G01X634676Y40400D02*
X641507D01*
G01X635350Y50116D02*
X634516Y50950D01*
G01X635350Y44123D02*
Y50116D01*
G01X637000Y50800D02*
X635200Y52600D01*
G01X637000Y44807D02*
Y50800D01*
G01X646100Y53466D02*
X641716Y57850D01*
G01X646100Y52592D02*
Y53466D01*
G01X648600Y50092D02*
X646100Y52592D01*
G01X648600Y46000D02*
Y50092D01*
G01X650100Y44500D02*
X648600Y46000D01*
G01X647750Y54150D02*
X642400Y59500D01*
G01X647750Y53276D02*
Y54150D01*
G01X650250Y50776D02*
X647750Y53276D01*
G01X650500Y55466D02*
X643516Y62450D01*
G01X652150Y56150D02*
X644200Y64100D01*
G01X656175Y28282D02*
Y41703D01*
G01X650200Y22307D02*
X656175Y28282D01*
G01X650200Y13945D02*
Y22307D01*
G01X650100Y36623D02*
Y44500D01*
G01X652000Y34723D02*
X650100Y36623D01*
G01X652000Y30541D02*
Y34723D01*
G01X651750Y37307D02*
Y45184D01*
G01X653325Y35732D02*
X651750Y37307D01*
G01X653325Y29532D02*
Y35732D01*
G01X654800Y42662D02*
X657200Y45062D01*
G01X654800Y29241D02*
Y42662D01*
G01X656175Y41703D02*
X658850Y44378D01*
G01X650250Y46684D02*
Y50776D01*
G01X651750Y45184D02*
X650250Y46684D01*
G01X650500Y54416D02*
Y55466D01*
G01X653366Y51550D02*
X650500Y54416D01*
G01X656016Y51550D02*
X653366D01*
G01X657200Y50366D02*
X656016Y51550D01*
G01X657200Y45062D02*
Y50366D01*
G01X652150Y55100D02*
Y56150D01*
G01X654050Y53200D02*
X652150Y55100D01*
G01X656700Y53200D02*
X654050D01*
G01X658850Y51050D02*
X656700Y53200D01*
G01X658850Y44378D02*
Y51050D01*
M02*
